FILE_TYPE = MACRO_DRAWING;
SET COLOR_WIRE YELLOW;
SET COLOR_PROP ORANGE;
SET COLOR_DOT WHITE;
SET COLOR_ARC YELLOW;
SET COLOR_BODY GREEN;
SET COLOR_NOTE PURPLE;
SET PROP_DISPLAY VALUE;
SET PAGE_NUMBER P104;
FORCEADD UNIVERSAL_GND..1
(-3100 -250);
FORCEPROP 3 LASTPIN (-3100 -200) SIG_NAME GND\g
J 0
(-3090 -190);
DISPLAY 0.659574 (-3090 -190);
PAINT MONO (-3090 -190);
DISPLAY INVISIBLE (-3090 -190);
FORCEPROP 1 LAST PATH I1
J 0
(-3025 -250);
DISPLAY 0.872340 (-3025 -250);
PAINT AQUA (-3025 -250);
DISPLAY INVISIBLE (-3025 -250);
FORCEPROP 1 LAST HDL_POWER GND
J 1
(-3075 -325);
DISPLAY 0.872340 (-3075 -325);
PAINT GREEN (-3075 -325);
DISPLAY INVISIBLE (-3075 -325);
FORCEPROP 2 LAST CDS_LIB logical_power
J 0
(-3100 -250);
PAINT MONO (-3100 -250);
DISPLAY INVISIBLE (-3100 -250);
FORCEADD OFFPAGE..1
(-4250 1775);
FORCEPROP 2 LAST $XR1 105 
J 0
(-4591 1775);
DISPLAY 0.638298 (-4591 1775);
PAINT MONO (-4591 1775);
FORCEPROP 2 LAST $XR0 54 
J 0
(-4471 1775);
DISPLAY 0.638298 (-4471 1775);
PAINT MONO (-4471 1775);
FORCEPROP 2 LAST CDS_LIB standard
J 0
(-4250 1775);
PAINT MONO (-4250 1775);
DISPLAY INVISIBLE (-4250 1775);
FORCEPROP 1 LAST OFFPAGE TRUE
J 0
(-3925 1650);
DISPLAY 0.872340 (-3925 1650);
DISPLAY INVISIBLE (-3925 1650);
FORCEPROP 1 LAST COMMENT_BODY TRUE
J 0
(-4125 1675);
DISPLAY 0.872340 (-4125 1675);
PAINT GREEN (-4125 1675);
DISPLAY INVISIBLE (-4125 1675);
FORCEPROP 2 LAST PATH I10
J 0
(-4200 1850);
DISPLAY 1.021277 (-4200 1850);
DISPLAY INVISIBLE (-4200 1850);
FORCEADD TAP..1
(-1675 3375);
FORCEPROP 3 LASTPIN (-1725 3375) SIG_NAME M_D_CPU1_SA_DQ<16>
J 0
(-1715 3385);
DISPLAY 0.659574 (-1715 3385);
PAINT MONO (-1715 3385);
DISPLAY INVISIBLE (-1715 3385);
FORCEPROP 1 LASTPIN (-1725 3375) BN 16
J 0
(-1737 3383);
DISPLAY 0.680851 (-1737 3383);
PAINT GREEN (-1737 3383);
FORCEPROP 2 LAST CDS_LIB standard
J 0
(-1675 3375);
PAINT MONO (-1675 3375);
DISPLAY INVISIBLE (-1675 3375);
FORCEPROP 1 LAST BODY_TYPE PLUMBING
J 0
(-1675 3425);
DISPLAY 0.872340 (-1675 3425);
PAINT GREEN (-1675 3425);
DISPLAY INVISIBLE (-1675 3425);
FORCEPROP 1 LAST HDL_TAP TRUE
J 0
(-1350 3250);
DISPLAY 0.872340 (-1350 3250);
DISPLAY INVISIBLE (-1350 3250);
FORCEPROP 1 LAST PATH I100
J 0
(-1677 3375);
DISPLAY 0.872340 (-1677 3375);
PAINT GREEN (-1677 3375);
DISPLAY INVISIBLE (-1677 3375);
FORCEADD TAP..1
(-1675 3325);
FORCEPROP 3 LASTPIN (-1725 3325) SIG_NAME M_D_CPU1_SA_DQ<15>
J 0
(-1715 3335);
DISPLAY 0.659574 (-1715 3335);
PAINT MONO (-1715 3335);
DISPLAY INVISIBLE (-1715 3335);
FORCEPROP 1 LASTPIN (-1725 3325) BN 15
J 0
(-1737 3333);
DISPLAY 0.680851 (-1737 3333);
PAINT GREEN (-1737 3333);
FORCEPROP 2 LAST CDS_LIB standard
J 0
(-1675 3325);
PAINT MONO (-1675 3325);
DISPLAY INVISIBLE (-1675 3325);
FORCEPROP 1 LAST BODY_TYPE PLUMBING
J 0
(-1675 3375);
DISPLAY 0.872340 (-1675 3375);
PAINT GREEN (-1675 3375);
DISPLAY INVISIBLE (-1675 3375);
FORCEPROP 1 LAST HDL_TAP TRUE
J 0
(-1350 3200);
DISPLAY 0.872340 (-1350 3200);
DISPLAY INVISIBLE (-1350 3200);
FORCEPROP 1 LAST PATH I101
J 0
(-1677 3325);
DISPLAY 0.872340 (-1677 3325);
PAINT GREEN (-1677 3325);
DISPLAY INVISIBLE (-1677 3325);
FORCEADD TAP..1
(-1675 3225);
FORCEPROP 3 LASTPIN (-1725 3225) SIG_NAME M_D_CPU1_SA_DQ<13>
J 0
(-1715 3235);
DISPLAY 0.659574 (-1715 3235);
PAINT MONO (-1715 3235);
DISPLAY INVISIBLE (-1715 3235);
FORCEPROP 1 LASTPIN (-1725 3225) BN 13
J 0
(-1737 3233);
DISPLAY 0.680851 (-1737 3233);
PAINT GREEN (-1737 3233);
FORCEPROP 2 LAST CDS_LIB standard
J 0
(-1675 3225);
PAINT MONO (-1675 3225);
DISPLAY INVISIBLE (-1675 3225);
FORCEPROP 1 LAST BODY_TYPE PLUMBING
J 0
(-1675 3275);
DISPLAY 0.872340 (-1675 3275);
PAINT GREEN (-1675 3275);
DISPLAY INVISIBLE (-1675 3275);
FORCEPROP 1 LAST HDL_TAP TRUE
J 0
(-1350 3100);
DISPLAY 0.872340 (-1350 3100);
DISPLAY INVISIBLE (-1350 3100);
FORCEPROP 1 LAST PATH I102
J 0
(-1677 3225);
DISPLAY 0.872340 (-1677 3225);
PAINT GREEN (-1677 3225);
DISPLAY INVISIBLE (-1677 3225);
FORCEADD TAP..1
(-1675 3275);
FORCEPROP 3 LASTPIN (-1725 3275) SIG_NAME M_D_CPU1_SA_DQ<14>
J 0
(-1715 3285);
DISPLAY 0.659574 (-1715 3285);
PAINT MONO (-1715 3285);
DISPLAY INVISIBLE (-1715 3285);
FORCEPROP 1 LASTPIN (-1725 3275) BN 14
J 0
(-1737 3283);
DISPLAY 0.680851 (-1737 3283);
PAINT GREEN (-1737 3283);
FORCEPROP 2 LAST CDS_LIB standard
J 0
(-1675 3275);
PAINT MONO (-1675 3275);
DISPLAY INVISIBLE (-1675 3275);
FORCEPROP 1 LAST BODY_TYPE PLUMBING
J 0
(-1675 3325);
DISPLAY 0.872340 (-1675 3325);
PAINT GREEN (-1675 3325);
DISPLAY INVISIBLE (-1675 3325);
FORCEPROP 1 LAST HDL_TAP TRUE
J 0
(-1350 3150);
DISPLAY 0.872340 (-1350 3150);
DISPLAY INVISIBLE (-1350 3150);
FORCEPROP 1 LAST PATH I103
J 0
(-1677 3275);
DISPLAY 0.872340 (-1677 3275);
PAINT GREEN (-1677 3275);
DISPLAY INVISIBLE (-1677 3275);
FORCEADD TAP..1
(-1675 3175);
FORCEPROP 3 LASTPIN (-1725 3175) SIG_NAME M_D_CPU1_SA_DQ<12>
J 0
(-1715 3185);
DISPLAY 0.659574 (-1715 3185);
PAINT MONO (-1715 3185);
DISPLAY INVISIBLE (-1715 3185);
FORCEPROP 1 LASTPIN (-1725 3175) BN 12
J 0
(-1737 3183);
DISPLAY 0.680851 (-1737 3183);
PAINT GREEN (-1737 3183);
FORCEPROP 2 LAST CDS_LIB standard
J 0
(-1675 3175);
PAINT MONO (-1675 3175);
DISPLAY INVISIBLE (-1675 3175);
FORCEPROP 1 LAST BODY_TYPE PLUMBING
J 0
(-1675 3225);
DISPLAY 0.872340 (-1675 3225);
PAINT GREEN (-1675 3225);
DISPLAY INVISIBLE (-1675 3225);
FORCEPROP 1 LAST HDL_TAP TRUE
J 0
(-1350 3050);
DISPLAY 0.872340 (-1350 3050);
DISPLAY INVISIBLE (-1350 3050);
FORCEPROP 1 LAST PATH I104
J 0
(-1677 3175);
DISPLAY 0.872340 (-1677 3175);
PAINT GREEN (-1677 3175);
DISPLAY INVISIBLE (-1677 3175);
FORCEADD TAP..1
(-1675 3425);
FORCEPROP 3 LASTPIN (-1725 3425) SIG_NAME M_D_CPU1_SA_DQ<17>
J 0
(-1715 3435);
DISPLAY 0.659574 (-1715 3435);
PAINT MONO (-1715 3435);
DISPLAY INVISIBLE (-1715 3435);
FORCEPROP 1 LASTPIN (-1725 3425) BN 17
J 0
(-1737 3433);
DISPLAY 0.680851 (-1737 3433);
PAINT GREEN (-1737 3433);
FORCEPROP 2 LAST CDS_LIB standard
J 0
(-1675 3425);
PAINT MONO (-1675 3425);
DISPLAY INVISIBLE (-1675 3425);
FORCEPROP 1 LAST BODY_TYPE PLUMBING
J 0
(-1675 3475);
DISPLAY 0.872340 (-1675 3475);
PAINT GREEN (-1675 3475);
DISPLAY INVISIBLE (-1675 3475);
FORCEPROP 1 LAST HDL_TAP TRUE
J 0
(-1350 3300);
DISPLAY 0.872340 (-1350 3300);
DISPLAY INVISIBLE (-1350 3300);
FORCEPROP 1 LAST PATH I105
J 0
(-1677 3425);
DISPLAY 0.872340 (-1677 3425);
PAINT GREEN (-1677 3425);
DISPLAY INVISIBLE (-1677 3425);
FORCEADD TAP..1
(-1675 3525);
FORCEPROP 3 LASTPIN (-1725 3525) SIG_NAME M_D_CPU1_SA_DQ<19>
J 0
(-1715 3535);
DISPLAY 0.659574 (-1715 3535);
PAINT MONO (-1715 3535);
DISPLAY INVISIBLE (-1715 3535);
FORCEPROP 1 LASTPIN (-1725 3525) BN 19
J 0
(-1737 3533);
DISPLAY 0.680851 (-1737 3533);
PAINT GREEN (-1737 3533);
FORCEPROP 2 LAST CDS_LIB standard
J 0
(-1675 3525);
PAINT MONO (-1675 3525);
DISPLAY INVISIBLE (-1675 3525);
FORCEPROP 1 LAST BODY_TYPE PLUMBING
J 0
(-1675 3575);
DISPLAY 0.872340 (-1675 3575);
PAINT GREEN (-1675 3575);
DISPLAY INVISIBLE (-1675 3575);
FORCEPROP 1 LAST HDL_TAP TRUE
J 0
(-1350 3400);
DISPLAY 0.872340 (-1350 3400);
DISPLAY INVISIBLE (-1350 3400);
FORCEPROP 1 LAST PATH I106
J 0
(-1677 3525);
DISPLAY 0.872340 (-1677 3525);
PAINT GREEN (-1677 3525);
DISPLAY INVISIBLE (-1677 3525);
FORCEADD TAP..1
(-1675 3475);
FORCEPROP 3 LASTPIN (-1725 3475) SIG_NAME M_D_CPU1_SA_DQ<18>
J 0
(-1715 3485);
DISPLAY 0.659574 (-1715 3485);
PAINT MONO (-1715 3485);
DISPLAY INVISIBLE (-1715 3485);
FORCEPROP 1 LASTPIN (-1725 3475) BN 18
J 0
(-1737 3483);
DISPLAY 0.680851 (-1737 3483);
PAINT GREEN (-1737 3483);
FORCEPROP 2 LAST CDS_LIB standard
J 0
(-1675 3475);
PAINT MONO (-1675 3475);
DISPLAY INVISIBLE (-1675 3475);
FORCEPROP 1 LAST BODY_TYPE PLUMBING
J 0
(-1675 3525);
DISPLAY 0.872340 (-1675 3525);
PAINT GREEN (-1675 3525);
DISPLAY INVISIBLE (-1675 3525);
FORCEPROP 1 LAST HDL_TAP TRUE
J 0
(-1350 3350);
DISPLAY 0.872340 (-1350 3350);
DISPLAY INVISIBLE (-1350 3350);
FORCEPROP 1 LAST PATH I107
J 0
(-1677 3475);
DISPLAY 0.872340 (-1677 3475);
PAINT GREEN (-1677 3475);
DISPLAY INVISIBLE (-1677 3475);
FORCEADD TAP..1
(-1675 3575);
FORCEPROP 3 LASTPIN (-1725 3575) SIG_NAME M_D_CPU1_SA_DQ<20>
J 0
(-1715 3585);
DISPLAY 0.659574 (-1715 3585);
PAINT MONO (-1715 3585);
DISPLAY INVISIBLE (-1715 3585);
FORCEPROP 1 LASTPIN (-1725 3575) BN 20
J 0
(-1737 3583);
DISPLAY 0.680851 (-1737 3583);
PAINT GREEN (-1737 3583);
FORCEPROP 2 LAST CDS_LIB standard
J 0
(-1675 3575);
PAINT MONO (-1675 3575);
DISPLAY INVISIBLE (-1675 3575);
FORCEPROP 1 LAST BODY_TYPE PLUMBING
J 0
(-1675 3625);
DISPLAY 0.872340 (-1675 3625);
PAINT GREEN (-1675 3625);
DISPLAY INVISIBLE (-1675 3625);
FORCEPROP 1 LAST HDL_TAP TRUE
J 0
(-1350 3450);
DISPLAY 0.872340 (-1350 3450);
DISPLAY INVISIBLE (-1350 3450);
FORCEPROP 1 LAST PATH I108
J 0
(-1677 3575);
DISPLAY 0.872340 (-1677 3575);
PAINT GREEN (-1677 3575);
DISPLAY INVISIBLE (-1677 3575);
FORCEADD TAP..1
(-1675 3625);
FORCEPROP 3 LASTPIN (-1725 3625) SIG_NAME M_D_CPU1_SA_DQ<21>
J 0
(-1715 3635);
DISPLAY 0.659574 (-1715 3635);
PAINT MONO (-1715 3635);
DISPLAY INVISIBLE (-1715 3635);
FORCEPROP 1 LASTPIN (-1725 3625) BN 21
J 0
(-1737 3633);
DISPLAY 0.680851 (-1737 3633);
PAINT GREEN (-1737 3633);
FORCEPROP 2 LAST CDS_LIB standard
J 0
(-1675 3625);
PAINT MONO (-1675 3625);
DISPLAY INVISIBLE (-1675 3625);
FORCEPROP 1 LAST BODY_TYPE PLUMBING
J 0
(-1675 3675);
DISPLAY 0.872340 (-1675 3675);
PAINT GREEN (-1675 3675);
DISPLAY INVISIBLE (-1675 3675);
FORCEPROP 1 LAST HDL_TAP TRUE
J 0
(-1350 3500);
DISPLAY 0.872340 (-1350 3500);
DISPLAY INVISIBLE (-1350 3500);
FORCEPROP 1 LAST PATH I109
J 0
(-1677 3625);
DISPLAY 0.872340 (-1677 3625);
PAINT GREEN (-1677 3625);
DISPLAY INVISIBLE (-1677 3625);
FORCEADD OFFPAGE..1
(-4250 1875);
FORCEPROP 2 LAST $XR3 105 
J 0
(-4622 1839);
DISPLAY 0.638298 (-4622 1839);
PAINT MONO (-4622 1839);
FORCEPROP 2 LAST $XR2 103 
J 0
(-4502 1839);
DISPLAY 0.638298 (-4502 1839);
PAINT MONO (-4502 1839);
FORCEPROP 2 LAST $XR1 102 
J 0
(-4622 1875);
DISPLAY 0.638298 (-4622 1875);
PAINT MONO (-4622 1875);
FORCEPROP 2 LAST $XR0 130 
J 0
(-4502 1875);
DISPLAY 0.638298 (-4502 1875);
PAINT MONO (-4502 1875);
FORCEPROP 2 LAST CDS_LIB standard
J 0
(-4250 1875);
PAINT MONO (-4250 1875);
DISPLAY INVISIBLE (-4250 1875);
FORCEPROP 1 LAST OFFPAGE TRUE
J 0
(-3925 1750);
DISPLAY 0.872340 (-3925 1750);
DISPLAY INVISIBLE (-3925 1750);
FORCEPROP 1 LAST COMMENT_BODY TRUE
J 0
(-4125 1775);
DISPLAY 0.872340 (-4125 1775);
PAINT GREEN (-4125 1775);
DISPLAY INVISIBLE (-4125 1775);
FORCEPROP 2 LAST PATH I11
J 0
(-4200 1950);
DISPLAY 1.021277 (-4200 1950);
DISPLAY INVISIBLE (-4200 1950);
FORCEADD TAP..1
(-1675 3675);
FORCEPROP 3 LASTPIN (-1725 3675) SIG_NAME M_D_CPU1_SA_DQ<22>
J 0
(-1715 3685);
DISPLAY 0.659574 (-1715 3685);
PAINT MONO (-1715 3685);
DISPLAY INVISIBLE (-1715 3685);
FORCEPROP 1 LASTPIN (-1725 3675) BN 22
J 0
(-1737 3683);
DISPLAY 0.680851 (-1737 3683);
PAINT GREEN (-1737 3683);
FORCEPROP 2 LAST CDS_LIB standard
J 0
(-1675 3675);
DISPLAY INVISIBLE (-1675 3675);
FORCEPROP 1 LAST BODY_TYPE PLUMBING
J 0
(-1675 3725);
DISPLAY 0.872340 (-1675 3725);
PAINT GREEN (-1675 3725);
DISPLAY INVISIBLE (-1675 3725);
FORCEPROP 1 LAST HDL_TAP TRUE
J 0
(-1350 3550);
DISPLAY 0.872340 (-1350 3550);
DISPLAY INVISIBLE (-1350 3550);
FORCEPROP 1 LAST PATH I110
J 0
(-1677 3675);
DISPLAY 0.872340 (-1677 3675);
PAINT GREEN (-1677 3675);
DISPLAY INVISIBLE (-1677 3675);
FORCEADD TAP..1
(-1675 3725);
FORCEPROP 3 LASTPIN (-1725 3725) SIG_NAME M_D_CPU1_SA_DQ<23>
J 0
(-1715 3735);
DISPLAY 0.659574 (-1715 3735);
PAINT MONO (-1715 3735);
DISPLAY INVISIBLE (-1715 3735);
FORCEPROP 1 LASTPIN (-1725 3725) BN 23
J 0
(-1737 3733);
DISPLAY 0.680851 (-1737 3733);
PAINT GREEN (-1737 3733);
FORCEPROP 2 LAST CDS_LIB standard
J 0
(-1675 3725);
DISPLAY INVISIBLE (-1675 3725);
FORCEPROP 1 LAST BODY_TYPE PLUMBING
J 0
(-1675 3775);
DISPLAY 0.872340 (-1675 3775);
PAINT GREEN (-1675 3775);
DISPLAY INVISIBLE (-1675 3775);
FORCEPROP 1 LAST HDL_TAP TRUE
J 0
(-1350 3600);
DISPLAY 0.872340 (-1350 3600);
DISPLAY INVISIBLE (-1350 3600);
FORCEPROP 1 LAST PATH I111
J 0
(-1677 3725);
DISPLAY 0.872340 (-1677 3725);
PAINT GREEN (-1677 3725);
DISPLAY INVISIBLE (-1677 3725);
FORCEADD TAP..1
(-1675 3775);
FORCEPROP 3 LASTPIN (-1725 3775) SIG_NAME M_D_CPU1_SA_DQ<24>
J 0
(-1715 3785);
DISPLAY 0.659574 (-1715 3785);
PAINT MONO (-1715 3785);
DISPLAY INVISIBLE (-1715 3785);
FORCEPROP 1 LASTPIN (-1725 3775) BN 24
J 0
(-1737 3783);
DISPLAY 0.680851 (-1737 3783);
PAINT GREEN (-1737 3783);
FORCEPROP 2 LAST CDS_LIB standard
J 0
(-1675 3775);
DISPLAY INVISIBLE (-1675 3775);
FORCEPROP 1 LAST BODY_TYPE PLUMBING
J 0
(-1675 3825);
DISPLAY 0.872340 (-1675 3825);
PAINT GREEN (-1675 3825);
DISPLAY INVISIBLE (-1675 3825);
FORCEPROP 1 LAST HDL_TAP TRUE
J 0
(-1350 3650);
DISPLAY 0.872340 (-1350 3650);
DISPLAY INVISIBLE (-1350 3650);
FORCEPROP 1 LAST PATH I112
J 0
(-1677 3775);
DISPLAY 0.872340 (-1677 3775);
PAINT GREEN (-1677 3775);
DISPLAY INVISIBLE (-1677 3775);
FORCEADD TAP..1
(-1675 3875);
FORCEPROP 3 LASTPIN (-1725 3875) SIG_NAME M_D_CPU1_SA_DQ<26>
J 0
(-1715 3885);
DISPLAY 0.659574 (-1715 3885);
PAINT MONO (-1715 3885);
DISPLAY INVISIBLE (-1715 3885);
FORCEPROP 1 LASTPIN (-1725 3875) BN 26
J 0
(-1737 3883);
DISPLAY 0.680851 (-1737 3883);
PAINT GREEN (-1737 3883);
FORCEPROP 2 LAST CDS_LIB standard
J 0
(-1675 3875);
DISPLAY INVISIBLE (-1675 3875);
FORCEPROP 1 LAST BODY_TYPE PLUMBING
J 0
(-1675 3925);
DISPLAY 0.872340 (-1675 3925);
PAINT GREEN (-1675 3925);
DISPLAY INVISIBLE (-1675 3925);
FORCEPROP 1 LAST HDL_TAP TRUE
J 0
(-1350 3750);
DISPLAY 0.872340 (-1350 3750);
DISPLAY INVISIBLE (-1350 3750);
FORCEPROP 1 LAST PATH I113
J 0
(-1677 3875);
DISPLAY 0.872340 (-1677 3875);
PAINT GREEN (-1677 3875);
DISPLAY INVISIBLE (-1677 3875);
FORCEADD TAP..1
(-1675 3825);
FORCEPROP 3 LASTPIN (-1725 3825) SIG_NAME M_D_CPU1_SA_DQ<25>
J 0
(-1715 3835);
DISPLAY 0.659574 (-1715 3835);
PAINT MONO (-1715 3835);
DISPLAY INVISIBLE (-1715 3835);
FORCEPROP 1 LASTPIN (-1725 3825) BN 25
J 0
(-1737 3833);
DISPLAY 0.680851 (-1737 3833);
PAINT GREEN (-1737 3833);
FORCEPROP 2 LAST CDS_LIB standard
J 0
(-1675 3825);
DISPLAY INVISIBLE (-1675 3825);
FORCEPROP 1 LAST BODY_TYPE PLUMBING
J 0
(-1675 3875);
DISPLAY 0.872340 (-1675 3875);
PAINT GREEN (-1675 3875);
DISPLAY INVISIBLE (-1675 3875);
FORCEPROP 1 LAST HDL_TAP TRUE
J 0
(-1350 3700);
DISPLAY 0.872340 (-1350 3700);
DISPLAY INVISIBLE (-1350 3700);
FORCEPROP 1 LAST PATH I114
J 0
(-1677 3825);
DISPLAY 0.872340 (-1677 3825);
PAINT GREEN (-1677 3825);
DISPLAY INVISIBLE (-1677 3825);
FORCEADD TAP..1
(-1675 3925);
FORCEPROP 3 LASTPIN (-1725 3925) SIG_NAME M_D_CPU1_SA_DQ<27>
J 0
(-1715 3935);
DISPLAY 0.659574 (-1715 3935);
PAINT MONO (-1715 3935);
DISPLAY INVISIBLE (-1715 3935);
FORCEPROP 1 LASTPIN (-1725 3925) BN 27
J 0
(-1737 3933);
DISPLAY 0.680851 (-1737 3933);
PAINT GREEN (-1737 3933);
FORCEPROP 2 LAST CDS_LIB standard
J 0
(-1675 3925);
DISPLAY INVISIBLE (-1675 3925);
FORCEPROP 1 LAST BODY_TYPE PLUMBING
J 0
(-1675 3975);
DISPLAY 0.872340 (-1675 3975);
PAINT GREEN (-1675 3975);
DISPLAY INVISIBLE (-1675 3975);
FORCEPROP 1 LAST HDL_TAP TRUE
J 0
(-1350 3800);
DISPLAY 0.872340 (-1350 3800);
DISPLAY INVISIBLE (-1350 3800);
FORCEPROP 1 LAST PATH I115
J 0
(-1677 3925);
DISPLAY 0.872340 (-1677 3925);
PAINT GREEN (-1677 3925);
DISPLAY INVISIBLE (-1677 3925);
FORCEADD TAP..1
(-1675 4025);
FORCEPROP 3 LASTPIN (-1725 4025) SIG_NAME M_D_CPU1_SA_DQ<29>
J 0
(-1715 4035);
DISPLAY 0.659574 (-1715 4035);
PAINT MONO (-1715 4035);
DISPLAY INVISIBLE (-1715 4035);
FORCEPROP 1 LASTPIN (-1725 4025) BN 29
J 0
(-1737 4033);
DISPLAY 0.680851 (-1737 4033);
PAINT GREEN (-1737 4033);
FORCEPROP 2 LAST CDS_LIB standard
J 0
(-1675 4025);
DISPLAY INVISIBLE (-1675 4025);
FORCEPROP 1 LAST BODY_TYPE PLUMBING
J 0
(-1675 4075);
DISPLAY 0.872340 (-1675 4075);
PAINT GREEN (-1675 4075);
DISPLAY INVISIBLE (-1675 4075);
FORCEPROP 1 LAST HDL_TAP TRUE
J 0
(-1350 3900);
DISPLAY 0.872340 (-1350 3900);
DISPLAY INVISIBLE (-1350 3900);
FORCEPROP 1 LAST PATH I116
J 0
(-1677 4025);
DISPLAY 0.872340 (-1677 4025);
PAINT GREEN (-1677 4025);
DISPLAY INVISIBLE (-1677 4025);
FORCEADD TAP..1
(-1675 3975);
FORCEPROP 3 LASTPIN (-1725 3975) SIG_NAME M_D_CPU1_SA_DQ<28>
J 0
(-1715 3985);
DISPLAY 0.659574 (-1715 3985);
PAINT MONO (-1715 3985);
DISPLAY INVISIBLE (-1715 3985);
FORCEPROP 1 LASTPIN (-1725 3975) BN 28
J 0
(-1737 3983);
DISPLAY 0.680851 (-1737 3983);
PAINT GREEN (-1737 3983);
FORCEPROP 2 LAST CDS_LIB standard
J 0
(-1675 3975);
DISPLAY INVISIBLE (-1675 3975);
FORCEPROP 1 LAST BODY_TYPE PLUMBING
J 0
(-1675 4025);
DISPLAY 0.872340 (-1675 4025);
PAINT GREEN (-1675 4025);
DISPLAY INVISIBLE (-1675 4025);
FORCEPROP 1 LAST HDL_TAP TRUE
J 0
(-1350 3850);
DISPLAY 0.872340 (-1350 3850);
DISPLAY INVISIBLE (-1350 3850);
FORCEPROP 1 LAST PATH I117
J 0
(-1677 3975);
DISPLAY 0.872340 (-1677 3975);
PAINT GREEN (-1677 3975);
DISPLAY INVISIBLE (-1677 3975);
FORCEADD TAP..1
(-1675 4125);
FORCEPROP 3 LASTPIN (-1725 4125) SIG_NAME M_D_CPU1_SA_DQ<31>
J 0
(-1715 4135);
DISPLAY 0.659574 (-1715 4135);
PAINT MONO (-1715 4135);
DISPLAY INVISIBLE (-1715 4135);
FORCEPROP 1 LASTPIN (-1725 4125) BN 31
J 0
(-1737 4133);
DISPLAY 0.680851 (-1737 4133);
PAINT GREEN (-1737 4133);
FORCEPROP 2 LAST CDS_LIB standard
J 0
(-1675 4125);
DISPLAY INVISIBLE (-1675 4125);
FORCEPROP 1 LAST BODY_TYPE PLUMBING
J 0
(-1675 4175);
DISPLAY 0.872340 (-1675 4175);
PAINT GREEN (-1675 4175);
DISPLAY INVISIBLE (-1675 4175);
FORCEPROP 1 LAST HDL_TAP TRUE
J 0
(-1350 4000);
DISPLAY 0.872340 (-1350 4000);
DISPLAY INVISIBLE (-1350 4000);
FORCEPROP 1 LAST PATH I118
J 0
(-1677 4125);
DISPLAY 0.872340 (-1677 4125);
PAINT GREEN (-1677 4125);
DISPLAY INVISIBLE (-1677 4125);
FORCEADD TAP..1
(-1675 4075);
FORCEPROP 3 LASTPIN (-1725 4075) SIG_NAME M_D_CPU1_SA_DQ<30>
J 0
(-1715 4085);
DISPLAY 0.659574 (-1715 4085);
PAINT MONO (-1715 4085);
DISPLAY INVISIBLE (-1715 4085);
FORCEPROP 1 LASTPIN (-1725 4075) BN 30
J 0
(-1737 4083);
DISPLAY 0.680851 (-1737 4083);
PAINT GREEN (-1737 4083);
FORCEPROP 2 LAST CDS_LIB standard
J 0
(-1675 4075);
DISPLAY INVISIBLE (-1675 4075);
FORCEPROP 1 LAST BODY_TYPE PLUMBING
J 0
(-1675 4125);
DISPLAY 0.872340 (-1675 4125);
PAINT GREEN (-1675 4125);
DISPLAY INVISIBLE (-1675 4125);
FORCEPROP 1 LAST HDL_TAP TRUE
J 0
(-1350 3950);
DISPLAY 0.872340 (-1350 3950);
DISPLAY INVISIBLE (-1350 3950);
FORCEPROP 1 LAST PATH I119
J 0
(-1677 4075);
DISPLAY 0.872340 (-1677 4075);
PAINT GREEN (-1677 4075);
DISPLAY INVISIBLE (-1677 4075);
FORCEADD VCC_CORE..1
(-4150 2000);
FORCEPROP 3 LASTPIN (-4150 1950) SIG_NAME P3V3_AUX\g
J 0
(-4140 1960);
DISPLAY 0.659574 (-4140 1960);
PAINT MONO (-4140 1960);
DISPLAY INVISIBLE (-4140 1960);
FORCEPROP 1 LAST HDL_POWER P3V3_AUX
J 1
(-4150 2050);
DISPLAY 1.148936 (-4150 2050);
PAINT GREEN (-4150 2050);
FORCEPROP 2 LAST CDS_LIB logical_power
J 0
(-4150 2000);
PAINT MONO (-4150 2000);
DISPLAY INVISIBLE (-4150 2000);
FORCEPROP 1 LAST PATH I12
J 0
(-4100 2025);
DISPLAY 0.872340 (-4100 2025);
PAINT AQUA (-4100 2025);
DISPLAY INVISIBLE (-4100 2025);
FORCEADD UNIVERSAL_GND..1
(50 -125);
FORCEPROP 3 LASTPIN (50 -75) SIG_NAME GND\g
J 0
(60 -65);
DISPLAY 0.659574 (60 -65);
PAINT MONO (60 -65);
DISPLAY INVISIBLE (60 -65);
FORCEPROP 1 LAST PATH I120
J 0
(125 -125);
DISPLAY 0.872340 (125 -125);
PAINT AQUA (125 -125);
DISPLAY INVISIBLE (125 -125);
FORCEPROP 1 LAST HDL_POWER GND
J 1
(75 -200);
DISPLAY 0.872340 (75 -200);
PAINT GREEN (75 -200);
DISPLAY INVISIBLE (75 -200);
FORCEPROP 2 LAST CDS_LIB logical_power
J 0
(50 -125);
PAINT MONO (50 -125);
DISPLAY INVISIBLE (50 -125);
FORCEADD UNIVERSAL_GND..1
(1675 -125);
FORCEPROP 3 LASTPIN (1675 -75) SIG_NAME GND\g
J 0
(1685 -65);
DISPLAY 0.659574 (1685 -65);
PAINT MONO (1685 -65);
DISPLAY INVISIBLE (1685 -65);
FORCEPROP 1 LAST PATH I121
J 0
(1750 -125);
DISPLAY 0.872340 (1750 -125);
PAINT AQUA (1750 -125);
DISPLAY INVISIBLE (1750 -125);
FORCEPROP 1 LAST HDL_POWER GND
J 1
(1700 -200);
DISPLAY 0.872340 (1700 -200);
PAINT GREEN (1700 -200);
DISPLAY INVISIBLE (1700 -200);
FORCEPROP 2 LAST CDS_LIB logical_power
J 0
(1675 -125);
PAINT MONO (1675 -125);
DISPLAY INVISIBLE (1675 -125);
FORCEADD Q_CAP..1
(50 250);
FORCEPROP 1 LAST PART_NUMBER CH5221MEB00
J 0
(100 100);
DISPLAY 0.978723 (100 100);
DISPLAY INVISIBLE (100 100);
FORCEPROP 1 LAST VOLTAGE 6.3V
J 0
(100 250);
DISPLAY 0.978723 (100 250);
FORCEPROP 1 LAST VALUE 2.2UF
J 0
(100 300);
DISPLAY 0.978723 (100 300);
FORCEPROP 1 LAST MATERIAL X6S
J 0
(100 150);
DISPLAY 0.978723 (100 150);
FORCEPROP 1 LAST TOLERANCE 20%
J 0
(100 200);
DISPLAY 0.978723 (100 200);
FORCEPROP 1 LAST PACK_TYPE C0402
J 0
(100 50);
DISPLAY 0.978723 (100 50);
FORCEPROP 1 LAST $LOCATION C68
J 0
(100 350);
DISPLAY 0.978723 (100 350);
FORCEPROP 1 LASTPIN (50 350) $PN 1
J 0
(60 330);
DISPLAY 0.787234 (60 330);
FORCEPROP 1 LASTPIN (50 150) $PN 2
J 0
(60 130);
DISPLAY 0.787234 (60 130);
FORCEPROP 2 LAST CDS_LIB pure_quanta
J 0
(50 250);
PAINT MONO (50 250);
DISPLAY INVISIBLE (50 250);
FORCEPROP 1 LAST PATH I122
J 0
(100 400);
DISPLAY 0.978723 (100 400);
PAINT WHITE (100 400);
DISPLAY INVISIBLE (100 400);
FORCEPROP 1 LAST $LOCATION C68
J 0
(100 450);
DISPLAY 1.021277 (100 450);
DISPLAY INVISIBLE (100 450);
FORCEPROP 2 LAST CDS_LOCATION C68
J 0
(100 450);
DISPLAY 1.021277 (100 450);
DISPLAY INVISIBLE (100 450);
FORCEPROP 2 LAST $SEC 1
J 0
(100 450);
DISPLAY 0.680851 (100 450);
PAINT MONO (100 450);
DISPLAY INVISIBLE (100 450);
FORCEPROP 2 LAST CDS_SEC 1
J 0
(100 450);
DISPLAY 1.021277 (100 450);
DISPLAY INVISIBLE (100 450);
FORCEADD VCC_CORE..1
(50 575);
FORCEPROP 3 LASTPIN (50 525) SIG_NAME P3V3_AUX\g
J 0
(60 535);
DISPLAY 0.659574 (60 535);
PAINT MONO (60 535);
DISPLAY INVISIBLE (60 535);
FORCEPROP 1 LAST HDL_POWER P3V3_AUX
J 1
(50 625);
DISPLAY 1.148936 (50 625);
PAINT GREEN (50 625);
FORCEPROP 2 LAST CDS_LIB logical_power
J 0
(50 575);
PAINT MONO (50 575);
DISPLAY INVISIBLE (50 575);
FORCEPROP 1 LAST PATH I123
J 0
(100 600);
DISPLAY 0.872340 (100 600);
PAINT AQUA (100 600);
DISPLAY INVISIBLE (100 600);
FORCEADD OFFPAGE..3
(-850 2500);
FORCEPROP 2 LAST $XR1 105 
J 0
(-546 2500);
DISPLAY 0.638298 (-546 2500);
PAINT MONO (-546 2500);
FORCEPROP 2 LAST $XR0 54 
J 0
(-636 2500);
DISPLAY 0.638298 (-636 2500);
PAINT MONO (-636 2500);
FORCEPROP 2 LAST CDS_LIB standard
J 2
(-850 2500);
DISPLAY INVISIBLE (-850 2500);
FORCEPROP 1 LAST OFFPAGE TRUE
J 0
(-525 2375);
DISPLAY 0.872340 (-525 2375);
DISPLAY INVISIBLE (-525 2375);
FORCEPROP 1 LAST COMMENT_BODY TRUE
J 0
(-900 2400);
DISPLAY 0.872340 (-900 2400);
PAINT GREEN (-900 2400);
DISPLAY INVISIBLE (-900 2400);
FORCEPROP 2 LAST PATH I124
J 0
(-650 2575);
DISPLAY 1.021277 (-650 2575);
DISPLAY INVISIBLE (-650 2575);
FORCEADD OFFPAGE..3
(-850 4150);
FORCEPROP 2 LAST $XR1 105 
J 0
(-546 4150);
DISPLAY 0.638298 (-546 4150);
PAINT MONO (-546 4150);
FORCEPROP 2 LAST $XR0 54 
J 0
(-636 4150);
DISPLAY 0.638298 (-636 4150);
PAINT MONO (-636 4150);
FORCEPROP 2 LAST CDS_LIB standard
J 2
(-850 4150);
DISPLAY INVISIBLE (-850 4150);
FORCEPROP 1 LAST OFFPAGE TRUE
J 0
(-525 4025);
DISPLAY 0.872340 (-525 4025);
DISPLAY INVISIBLE (-525 4025);
FORCEPROP 1 LAST COMMENT_BODY TRUE
J 0
(-900 4050);
DISPLAY 0.872340 (-900 4050);
PAINT GREEN (-900 4050);
DISPLAY INVISIBLE (-900 4050);
FORCEPROP 2 LAST PATH I125
J 0
(-650 4225);
DISPLAY 1.021277 (-650 4225);
DISPLAY INVISIBLE (-650 4225);
FORCEADD Q_CAP..1
(1050 250);
FORCEPROP 1 LAST PART_NUMBER CH6103KEA00
J 0
(1100 100);
DISPLAY 0.978723 (1100 100);
DISPLAY INVISIBLE (1100 100);
FORCEPROP 1 LAST VALUE 10UF
J 0
(1100 300);
DISPLAY 0.978723 (1100 300);
FORCEPROP 1 LAST PACK_TYPE C0805
J 0
(1100 50);
DISPLAY 0.978723 (1100 50);
FORCEPROP 1 LAST VOLTAGE 16V
J 0
(1100 250);
DISPLAY 0.978723 (1100 250);
FORCEPROP 1 LAST TOLERANCE 10%
J 0
(1100 200);
DISPLAY 0.978723 (1100 200);
FORCEPROP 1 LAST MATERIAL X6S
J 0
(1100 150);
DISPLAY 0.978723 (1100 150);
FORCEPROP 1 LAST $LOCATION C69
J 0
(1100 350);
DISPLAY 0.978723 (1100 350);
FORCEPROP 1 LASTPIN (1050 350) $PN 1
J 0
(1060 330);
DISPLAY 0.787234 (1060 330);
FORCEPROP 1 LASTPIN (1050 150) $PN 2
J 0
(1060 130);
DISPLAY 0.787234 (1060 130);
FORCEPROP 2 LAST CDS_LIB pure_quanta
J 0
(1050 250);
PAINT MONO (1050 250);
DISPLAY INVISIBLE (1050 250);
FORCEPROP 1 LAST PATH I127
J 0
(1100 400);
DISPLAY 0.978723 (1100 400);
PAINT WHITE (1100 400);
DISPLAY INVISIBLE (1100 400);
FORCEPROP 1 LAST $LOCATION C69
J 0
(1100 450);
DISPLAY 1.021277 (1100 450);
DISPLAY INVISIBLE (1100 450);
FORCEPROP 2 LAST CDS_LOCATION C69
J 0
(1100 450);
DISPLAY 1.021277 (1100 450);
DISPLAY INVISIBLE (1100 450);
FORCEPROP 2 LAST $SEC 1
J 0
(1100 450);
DISPLAY 0.680851 (1100 450);
PAINT MONO (1100 450);
DISPLAY INVISIBLE (1100 450);
FORCEPROP 2 LAST CDS_SEC 1
J 0
(1100 450);
DISPLAY 1.021277 (1100 450);
DISPLAY INVISIBLE (1100 450);
FORCEADD VCC_CORE..1
(1050 575);
FORCEPROP 3 LASTPIN (1050 525) SIG_NAME P12V_S3_AUX_CPU1_NVDIMM\g
J 0
(1060 535);
DISPLAY 0.659574 (1060 535);
PAINT MONO (1060 535);
DISPLAY INVISIBLE (1060 535);
FORCEPROP 1 LAST HDL_POWER P12V_S3_AUX_CPU1_NVDIMM
J 1
(1050 625);
DISPLAY 1.148936 (1050 625);
PAINT GREEN (1050 625);
FORCEPROP 2 LAST CDS_LIB logical_power
J 0
(1050 575);
PAINT MONO (1050 575);
DISPLAY INVISIBLE (1050 575);
FORCEPROP 1 LAST PATH I128
J 0
(1100 600);
DISPLAY 0.872340 (1100 600);
PAINT AQUA (1100 600);
DISPLAY INVISIBLE (1100 600);
FORCEADD Q_CAP..1
(1675 250);
FORCEPROP 1 LAST PART_NUMBER CH6103KEA00
J 0
(1725 100);
DISPLAY 0.978723 (1725 100);
DISPLAY INVISIBLE (1725 100);
FORCEPROP 1 LAST PACK_TYPE C0805
J 0
(1725 50);
DISPLAY 0.978723 (1725 50);
FORCEPROP 1 LAST VOLTAGE 16V
J 0
(1725 250);
DISPLAY 0.978723 (1725 250);
FORCEPROP 1 LAST TOLERANCE 10%
J 0
(1725 200);
DISPLAY 0.978723 (1725 200);
FORCEPROP 1 LAST VALUE 10UF
J 0
(1725 300);
DISPLAY 0.978723 (1725 300);
FORCEPROP 1 LAST MATERIAL X6S
J 0
(1725 150);
DISPLAY 0.978723 (1725 150);
FORCEPROP 1 LAST $LOCATION C70
J 0
(1725 350);
DISPLAY 0.978723 (1725 350);
FORCEPROP 1 LASTPIN (1675 350) $PN 1
J 0
(1685 330);
DISPLAY 0.787234 (1685 330);
FORCEPROP 1 LASTPIN (1675 150) $PN 2
J 0
(1685 130);
DISPLAY 0.787234 (1685 130);
FORCEPROP 2 LAST CDS_LIB pure_quanta
J 0
(1675 250);
PAINT MONO (1675 250);
DISPLAY INVISIBLE (1675 250);
FORCEPROP 1 LAST PATH I129
J 0
(1725 400);
DISPLAY 0.978723 (1725 400);
PAINT WHITE (1725 400);
DISPLAY INVISIBLE (1725 400);
FORCEPROP 1 LAST $LOCATION C70
J 0
(1725 450);
DISPLAY 1.021277 (1725 450);
DISPLAY INVISIBLE (1725 450);
FORCEPROP 2 LAST CDS_LOCATION C70
J 0
(1725 450);
DISPLAY 1.021277 (1725 450);
DISPLAY INVISIBLE (1725 450);
FORCEPROP 2 LAST $SEC 1
J 0
(1725 450);
DISPLAY 0.680851 (1725 450);
PAINT MONO (1725 450);
DISPLAY INVISIBLE (1725 450);
FORCEPROP 2 LAST CDS_SEC 1
J 0
(1725 450);
DISPLAY 1.021277 (1725 450);
DISPLAY INVISIBLE (1725 450);
FORCEADD OFFPAGE..3
R 2
(-4250 2300);
FORCEPROP 2 LAST $XR1 105 
J 0
(-4619 2300);
DISPLAY 0.638298 (-4619 2300);
PAINT MONO (-4619 2300);
FORCEPROP 2 LAST $XR0 54 
J 0
(-4499 2300);
DISPLAY 0.638298 (-4499 2300);
PAINT MONO (-4499 2300);
FORCEPROP 2 LAST CDS_LIB standard
J 0
(-4250 2300);
PAINT MONO (-4250 2300);
DISPLAY INVISIBLE (-4250 2300);
FORCEPROP 1 LAST OFFPAGE TRUE
J 2
(-4575 2175);
DISPLAY 0.872340 (-4575 2175);
DISPLAY INVISIBLE (-4575 2175);
FORCEPROP 1 LAST COMMENT_BODY TRUE
J 2
(-4200 2200);
DISPLAY 0.872340 (-4200 2200);
PAINT GREEN (-4200 2200);
DISPLAY INVISIBLE (-4200 2200);
FORCEPROP 2 LAST PATH I13
J 0
(-4200 2375);
DISPLAY 1.021277 (-4200 2375);
DISPLAY INVISIBLE (-4200 2375);
FORCEADD TAP..1
(1075 2275);
FORCEPROP 3 LASTPIN (1025 2275) SIG_NAME M_D_CPU1_SB_DQS_DP<1>
J 0
(1035 2285);
DISPLAY 0.659574 (1035 2285);
PAINT MONO (1035 2285);
DISPLAY INVISIBLE (1035 2285);
FORCEPROP 1 LASTPIN (1025 2275) BN 1
J 0
(1013 2283);
DISPLAY 0.680851 (1013 2283);
PAINT GREEN (1013 2283);
FORCEPROP 2 LAST CDS_LIB standard
J 0
(1075 2275);
DISPLAY INVISIBLE (1075 2275);
FORCEPROP 1 LAST BODY_TYPE PLUMBING
J 0
(1075 2325);
DISPLAY 0.872340 (1075 2325);
PAINT GREEN (1075 2325);
DISPLAY INVISIBLE (1075 2325);
FORCEPROP 1 LAST HDL_TAP TRUE
J 0
(1400 2150);
DISPLAY 0.872340 (1400 2150);
DISPLAY INVISIBLE (1400 2150);
FORCEPROP 1 LAST PATH I130
J 0
(1073 2275);
DISPLAY 0.872340 (1073 2275);
PAINT GREEN (1073 2275);
DISPLAY INVISIBLE (1073 2275);
FORCEADD TAP..1
(1075 2175);
FORCEPROP 3 LASTPIN (1025 2175) SIG_NAME M_D_CPU1_SB_DQS_DP<0>
J 0
(1035 2185);
DISPLAY 0.659574 (1035 2185);
PAINT MONO (1035 2185);
DISPLAY INVISIBLE (1035 2185);
FORCEPROP 1 LASTPIN (1025 2175) BN 0
J 0
(1013 2183);
DISPLAY 0.680851 (1013 2183);
PAINT GREEN (1013 2183);
FORCEPROP 2 LAST CDS_LIB standard
J 0
(1075 2175);
PAINT MONO (1075 2175);
DISPLAY INVISIBLE (1075 2175);
FORCEPROP 1 LAST BODY_TYPE PLUMBING
J 0
(1075 2225);
DISPLAY 0.872340 (1075 2225);
PAINT GREEN (1075 2225);
DISPLAY INVISIBLE (1075 2225);
FORCEPROP 1 LAST HDL_TAP TRUE
J 0
(1400 2050);
DISPLAY 0.872340 (1400 2050);
DISPLAY INVISIBLE (1400 2050);
FORCEPROP 1 LAST PATH I131
J 0
(1073 2175);
DISPLAY 0.872340 (1073 2175);
PAINT GREEN (1073 2175);
DISPLAY INVISIBLE (1073 2175);
FORCEADD TAP..1
(1075 2375);
FORCEPROP 3 LASTPIN (1025 2375) SIG_NAME M_D_CPU1_SB_DQS_DP<2>
J 0
(1035 2385);
DISPLAY 0.659574 (1035 2385);
PAINT MONO (1035 2385);
DISPLAY INVISIBLE (1035 2385);
FORCEPROP 1 LASTPIN (1025 2375) BN 2
J 0
(1013 2383);
DISPLAY 0.680851 (1013 2383);
PAINT GREEN (1013 2383);
FORCEPROP 2 LAST CDS_LIB standard
J 0
(1075 2375);
DISPLAY INVISIBLE (1075 2375);
FORCEPROP 1 LAST BODY_TYPE PLUMBING
J 0
(1075 2425);
DISPLAY 0.872340 (1075 2425);
PAINT GREEN (1075 2425);
DISPLAY INVISIBLE (1075 2425);
FORCEPROP 1 LAST HDL_TAP TRUE
J 0
(1400 2250);
DISPLAY 0.872340 (1400 2250);
DISPLAY INVISIBLE (1400 2250);
FORCEPROP 1 LAST PATH I132
J 0
(1073 2375);
DISPLAY 0.872340 (1073 2375);
PAINT GREEN (1073 2375);
DISPLAY INVISIBLE (1073 2375);
FORCEADD TAP..1
(1075 2575);
FORCEPROP 3 LASTPIN (1025 2575) SIG_NAME M_D_CPU1_SB_DQS_DP<4>
J 0
(1035 2585);
DISPLAY 0.659574 (1035 2585);
PAINT MONO (1035 2585);
DISPLAY INVISIBLE (1035 2585);
FORCEPROP 1 LASTPIN (1025 2575) BN 4
J 0
(1013 2583);
DISPLAY 0.680851 (1013 2583);
PAINT GREEN (1013 2583);
FORCEPROP 2 LAST CDS_LIB standard
J 0
(1075 2575);
PAINT MONO (1075 2575);
DISPLAY INVISIBLE (1075 2575);
FORCEPROP 1 LAST BODY_TYPE PLUMBING
J 0
(1075 2625);
DISPLAY 0.872340 (1075 2625);
PAINT GREEN (1075 2625);
DISPLAY INVISIBLE (1075 2625);
FORCEPROP 1 LAST HDL_TAP TRUE
J 0
(1400 2450);
DISPLAY 0.872340 (1400 2450);
DISPLAY INVISIBLE (1400 2450);
FORCEPROP 1 LAST PATH I133
J 0
(1073 2575);
DISPLAY 0.872340 (1073 2575);
PAINT GREEN (1073 2575);
DISPLAY INVISIBLE (1073 2575);
FORCEADD TAP..1
(1075 2475);
FORCEPROP 3 LASTPIN (1025 2475) SIG_NAME M_D_CPU1_SB_DQS_DP<3>
J 0
(1035 2485);
DISPLAY 0.659574 (1035 2485);
PAINT MONO (1035 2485);
DISPLAY INVISIBLE (1035 2485);
FORCEPROP 1 LASTPIN (1025 2475) BN 3
J 0
(1013 2483);
DISPLAY 0.680851 (1013 2483);
PAINT GREEN (1013 2483);
FORCEPROP 2 LAST CDS_LIB standard
J 0
(1075 2475);
PAINT MONO (1075 2475);
DISPLAY INVISIBLE (1075 2475);
FORCEPROP 1 LAST BODY_TYPE PLUMBING
J 0
(1075 2525);
DISPLAY 0.872340 (1075 2525);
PAINT GREEN (1075 2525);
DISPLAY INVISIBLE (1075 2525);
FORCEPROP 1 LAST HDL_TAP TRUE
J 0
(1400 2350);
DISPLAY 0.872340 (1400 2350);
DISPLAY INVISIBLE (1400 2350);
FORCEPROP 1 LAST PATH I134
J 0
(1073 2475);
DISPLAY 0.872340 (1073 2475);
PAINT GREEN (1073 2475);
DISPLAY INVISIBLE (1073 2475);
FORCEADD TAP..1
(1075 2775);
FORCEPROP 3 LASTPIN (1025 2775) SIG_NAME M_D_CPU1_SB_DQS_DP<6>
J 0
(1035 2785);
DISPLAY 0.659574 (1035 2785);
PAINT MONO (1035 2785);
DISPLAY INVISIBLE (1035 2785);
FORCEPROP 1 LASTPIN (1025 2775) BN 6
J 0
(1013 2783);
DISPLAY 0.680851 (1013 2783);
PAINT GREEN (1013 2783);
FORCEPROP 2 LAST CDS_LIB standard
J 0
(1075 2775);
DISPLAY INVISIBLE (1075 2775);
FORCEPROP 1 LAST BODY_TYPE PLUMBING
J 0
(1075 2825);
DISPLAY 0.872340 (1075 2825);
PAINT GREEN (1075 2825);
DISPLAY INVISIBLE (1075 2825);
FORCEPROP 1 LAST HDL_TAP TRUE
J 0
(1400 2650);
DISPLAY 0.872340 (1400 2650);
DISPLAY INVISIBLE (1400 2650);
FORCEPROP 1 LAST PATH I135
J 0
(1073 2775);
DISPLAY 0.872340 (1073 2775);
PAINT GREEN (1073 2775);
DISPLAY INVISIBLE (1073 2775);
FORCEADD TAP..1
(1075 2675);
FORCEPROP 3 LASTPIN (1025 2675) SIG_NAME M_D_CPU1_SB_DQS_DP<5>
J 0
(1035 2685);
DISPLAY 0.659574 (1035 2685);
PAINT MONO (1035 2685);
DISPLAY INVISIBLE (1035 2685);
FORCEPROP 1 LASTPIN (1025 2675) BN 5
J 0
(1013 2683);
DISPLAY 0.680851 (1013 2683);
PAINT GREEN (1013 2683);
FORCEPROP 2 LAST CDS_LIB standard
J 0
(1075 2675);
DISPLAY INVISIBLE (1075 2675);
FORCEPROP 1 LAST BODY_TYPE PLUMBING
J 0
(1075 2725);
DISPLAY 0.872340 (1075 2725);
PAINT GREEN (1075 2725);
DISPLAY INVISIBLE (1075 2725);
FORCEPROP 1 LAST HDL_TAP TRUE
J 0
(1400 2550);
DISPLAY 0.872340 (1400 2550);
DISPLAY INVISIBLE (1400 2550);
FORCEPROP 1 LAST PATH I136
J 0
(1073 2675);
DISPLAY 0.872340 (1073 2675);
PAINT GREEN (1073 2675);
DISPLAY INVISIBLE (1073 2675);
FORCEADD TAP..1
(1075 2875);
FORCEPROP 3 LASTPIN (1025 2875) SIG_NAME M_D_CPU1_SB_DQS_DP<7>
J 0
(1035 2885);
DISPLAY 0.659574 (1035 2885);
PAINT MONO (1035 2885);
DISPLAY INVISIBLE (1035 2885);
FORCEPROP 1 LASTPIN (1025 2875) BN 7
J 0
(1013 2883);
DISPLAY 0.680851 (1013 2883);
PAINT GREEN (1013 2883);
FORCEPROP 2 LAST CDS_LIB standard
J 0
(1075 2875);
DISPLAY INVISIBLE (1075 2875);
FORCEPROP 1 LAST BODY_TYPE PLUMBING
J 0
(1075 2925);
DISPLAY 0.872340 (1075 2925);
PAINT GREEN (1075 2925);
DISPLAY INVISIBLE (1075 2925);
FORCEPROP 1 LAST HDL_TAP TRUE
J 0
(1400 2750);
DISPLAY 0.872340 (1400 2750);
DISPLAY INVISIBLE (1400 2750);
FORCEPROP 1 LAST PATH I137
J 0
(1073 2875);
DISPLAY 0.872340 (1073 2875);
PAINT GREEN (1073 2875);
DISPLAY INVISIBLE (1073 2875);
FORCEADD TAP..1
(1075 3075);
FORCEPROP 3 LASTPIN (1025 3075) SIG_NAME M_D_CPU1_SB_DQS_DP<9>
J 0
(1035 3085);
DISPLAY 0.659574 (1035 3085);
PAINT MONO (1035 3085);
DISPLAY INVISIBLE (1035 3085);
FORCEPROP 1 LASTPIN (1025 3075) BN 9
J 0
(1013 3083);
DISPLAY 0.680851 (1013 3083);
PAINT GREEN (1013 3083);
FORCEPROP 2 LAST CDS_LIB standard
J 0
(1075 3075);
DISPLAY INVISIBLE (1075 3075);
FORCEPROP 1 LAST BODY_TYPE PLUMBING
J 0
(1075 3125);
DISPLAY 0.872340 (1075 3125);
PAINT GREEN (1075 3125);
DISPLAY INVISIBLE (1075 3125);
FORCEPROP 1 LAST HDL_TAP TRUE
J 0
(1400 2950);
DISPLAY 0.872340 (1400 2950);
DISPLAY INVISIBLE (1400 2950);
FORCEPROP 1 LAST PATH I138
J 0
(1073 3075);
DISPLAY 0.872340 (1073 3075);
PAINT GREEN (1073 3075);
DISPLAY INVISIBLE (1073 3075);
FORCEADD TAP..1
(1075 2975);
FORCEPROP 3 LASTPIN (1025 2975) SIG_NAME M_D_CPU1_SB_DQS_DP<8>
J 0
(1035 2985);
DISPLAY 0.659574 (1035 2985);
PAINT MONO (1035 2985);
DISPLAY INVISIBLE (1035 2985);
FORCEPROP 1 LASTPIN (1025 2975) BN 8
J 0
(1013 2983);
DISPLAY 0.680851 (1013 2983);
PAINT GREEN (1013 2983);
FORCEPROP 2 LAST CDS_LIB standard
J 0
(1075 2975);
DISPLAY INVISIBLE (1075 2975);
FORCEPROP 1 LAST BODY_TYPE PLUMBING
J 0
(1075 3025);
DISPLAY 0.872340 (1075 3025);
PAINT GREEN (1075 3025);
DISPLAY INVISIBLE (1075 3025);
FORCEPROP 1 LAST HDL_TAP TRUE
J 0
(1400 2850);
DISPLAY 0.872340 (1400 2850);
DISPLAY INVISIBLE (1400 2850);
FORCEPROP 1 LAST PATH I139
J 0
(1073 2975);
DISPLAY 0.872340 (1073 2975);
PAINT GREEN (1073 2975);
DISPLAY INVISIBLE (1073 2975);
FORCEADD OFFPAGE..1
(-4250 2825);
FORCEPROP 2 LAST $XR0 54 
J 0
(-4471 2825);
DISPLAY 0.638298 (-4471 2825);
PAINT MONO (-4471 2825);
FORCEPROP 2 LAST CDS_LIB standard
J 0
(-4250 2825);
PAINT MONO (-4250 2825);
DISPLAY INVISIBLE (-4250 2825);
FORCEPROP 1 LAST OFFPAGE TRUE
J 0
(-3925 2700);
DISPLAY 0.872340 (-3925 2700);
DISPLAY INVISIBLE (-3925 2700);
FORCEPROP 1 LAST COMMENT_BODY TRUE
J 0
(-4125 2725);
DISPLAY 0.872340 (-4125 2725);
PAINT GREEN (-4125 2725);
DISPLAY INVISIBLE (-4125 2725);
FORCEPROP 2 LAST PATH I14
J 0
(-4200 2900);
DISPLAY 1.021277 (-4200 2900);
DISPLAY INVISIBLE (-4200 2900);
FORCEADD TAP..1
(1250 2125);
FORCEPROP 3 LASTPIN (1200 2125) SIG_NAME M_D_CPU1_SB_DQS_DN<0>
J 0
(1210 2135);
DISPLAY 0.659574 (1210 2135);
PAINT MONO (1210 2135);
DISPLAY INVISIBLE (1210 2135);
FORCEPROP 1 LASTPIN (1200 2125) BN 0
J 0
(1188 2133);
DISPLAY 0.680851 (1188 2133);
PAINT GREEN (1188 2133);
FORCEPROP 2 LAST CDS_LIB standard
J 0
(1250 2125);
PAINT MONO (1250 2125);
DISPLAY INVISIBLE (1250 2125);
FORCEPROP 1 LAST BODY_TYPE PLUMBING
J 0
(1250 2175);
DISPLAY 0.872340 (1250 2175);
PAINT GREEN (1250 2175);
DISPLAY INVISIBLE (1250 2175);
FORCEPROP 1 LAST HDL_TAP TRUE
J 0
(1575 2000);
DISPLAY 0.872340 (1575 2000);
DISPLAY INVISIBLE (1575 2000);
FORCEPROP 1 LAST PATH I140
J 0
(1248 2125);
DISPLAY 0.872340 (1248 2125);
PAINT GREEN (1248 2125);
DISPLAY INVISIBLE (1248 2125);
FORCEADD TAP..1
(1250 2225);
FORCEPROP 3 LASTPIN (1200 2225) SIG_NAME M_D_CPU1_SB_DQS_DN<1>
J 0
(1210 2235);
DISPLAY 0.659574 (1210 2235);
PAINT MONO (1210 2235);
DISPLAY INVISIBLE (1210 2235);
FORCEPROP 1 LASTPIN (1200 2225) BN 1
J 0
(1188 2233);
DISPLAY 0.680851 (1188 2233);
PAINT GREEN (1188 2233);
FORCEPROP 2 LAST CDS_LIB standard
J 0
(1250 2225);
DISPLAY INVISIBLE (1250 2225);
FORCEPROP 1 LAST BODY_TYPE PLUMBING
J 0
(1250 2275);
DISPLAY 0.872340 (1250 2275);
PAINT GREEN (1250 2275);
DISPLAY INVISIBLE (1250 2275);
FORCEPROP 1 LAST HDL_TAP TRUE
J 0
(1575 2100);
DISPLAY 0.872340 (1575 2100);
DISPLAY INVISIBLE (1575 2100);
FORCEPROP 1 LAST PATH I141
J 0
(1248 2225);
DISPLAY 0.872340 (1248 2225);
PAINT GREEN (1248 2225);
DISPLAY INVISIBLE (1248 2225);
FORCEADD TAP..1
(1250 2325);
FORCEPROP 3 LASTPIN (1200 2325) SIG_NAME M_D_CPU1_SB_DQS_DN<2>
J 0
(1210 2335);
DISPLAY 0.659574 (1210 2335);
PAINT MONO (1210 2335);
DISPLAY INVISIBLE (1210 2335);
FORCEPROP 1 LASTPIN (1200 2325) BN 2
J 0
(1188 2333);
DISPLAY 0.680851 (1188 2333);
PAINT GREEN (1188 2333);
FORCEPROP 2 LAST CDS_LIB standard
J 0
(1250 2325);
DISPLAY INVISIBLE (1250 2325);
FORCEPROP 1 LAST BODY_TYPE PLUMBING
J 0
(1250 2375);
DISPLAY 0.872340 (1250 2375);
PAINT GREEN (1250 2375);
DISPLAY INVISIBLE (1250 2375);
FORCEPROP 1 LAST HDL_TAP TRUE
J 0
(1575 2200);
DISPLAY 0.872340 (1575 2200);
DISPLAY INVISIBLE (1575 2200);
FORCEPROP 1 LAST PATH I142
J 0
(1248 2325);
DISPLAY 0.872340 (1248 2325);
PAINT GREEN (1248 2325);
DISPLAY INVISIBLE (1248 2325);
FORCEADD TAP..1
(1250 2425);
FORCEPROP 3 LASTPIN (1200 2425) SIG_NAME M_D_CPU1_SB_DQS_DN<3>
J 0
(1210 2435);
DISPLAY 0.659574 (1210 2435);
PAINT MONO (1210 2435);
DISPLAY INVISIBLE (1210 2435);
FORCEPROP 1 LASTPIN (1200 2425) BN 3
J 0
(1188 2433);
DISPLAY 0.680851 (1188 2433);
PAINT GREEN (1188 2433);
FORCEPROP 2 LAST CDS_LIB standard
J 0
(1250 2425);
PAINT MONO (1250 2425);
DISPLAY INVISIBLE (1250 2425);
FORCEPROP 1 LAST BODY_TYPE PLUMBING
J 0
(1250 2475);
DISPLAY 0.872340 (1250 2475);
PAINT GREEN (1250 2475);
DISPLAY INVISIBLE (1250 2475);
FORCEPROP 1 LAST HDL_TAP TRUE
J 0
(1575 2300);
DISPLAY 0.872340 (1575 2300);
DISPLAY INVISIBLE (1575 2300);
FORCEPROP 1 LAST PATH I143
J 0
(1248 2425);
DISPLAY 0.872340 (1248 2425);
PAINT GREEN (1248 2425);
DISPLAY INVISIBLE (1248 2425);
FORCEADD TAP..1
(1250 2525);
FORCEPROP 3 LASTPIN (1200 2525) SIG_NAME M_D_CPU1_SB_DQS_DN<4>
J 0
(1210 2535);
DISPLAY 0.659574 (1210 2535);
PAINT MONO (1210 2535);
DISPLAY INVISIBLE (1210 2535);
FORCEPROP 1 LASTPIN (1200 2525) BN 4
J 0
(1188 2533);
DISPLAY 0.680851 (1188 2533);
PAINT GREEN (1188 2533);
FORCEPROP 2 LAST CDS_LIB standard
J 0
(1250 2525);
PAINT MONO (1250 2525);
DISPLAY INVISIBLE (1250 2525);
FORCEPROP 1 LAST BODY_TYPE PLUMBING
J 0
(1250 2575);
DISPLAY 0.872340 (1250 2575);
PAINT GREEN (1250 2575);
DISPLAY INVISIBLE (1250 2575);
FORCEPROP 1 LAST HDL_TAP TRUE
J 0
(1575 2400);
DISPLAY 0.872340 (1575 2400);
DISPLAY INVISIBLE (1575 2400);
FORCEPROP 1 LAST PATH I144
J 0
(1248 2525);
DISPLAY 0.872340 (1248 2525);
PAINT GREEN (1248 2525);
DISPLAY INVISIBLE (1248 2525);
FORCEADD TAP..1
(1250 2625);
FORCEPROP 3 LASTPIN (1200 2625) SIG_NAME M_D_CPU1_SB_DQS_DN<5>
J 0
(1210 2635);
DISPLAY 0.659574 (1210 2635);
PAINT MONO (1210 2635);
DISPLAY INVISIBLE (1210 2635);
FORCEPROP 1 LASTPIN (1200 2625) BN 5
J 0
(1188 2633);
DISPLAY 0.680851 (1188 2633);
PAINT GREEN (1188 2633);
FORCEPROP 2 LAST CDS_LIB standard
J 0
(1250 2625);
DISPLAY INVISIBLE (1250 2625);
FORCEPROP 1 LAST BODY_TYPE PLUMBING
J 0
(1250 2675);
DISPLAY 0.872340 (1250 2675);
PAINT GREEN (1250 2675);
DISPLAY INVISIBLE (1250 2675);
FORCEPROP 1 LAST HDL_TAP TRUE
J 0
(1575 2500);
DISPLAY 0.872340 (1575 2500);
DISPLAY INVISIBLE (1575 2500);
FORCEPROP 1 LAST PATH I145
J 0
(1248 2625);
DISPLAY 0.872340 (1248 2625);
PAINT GREEN (1248 2625);
DISPLAY INVISIBLE (1248 2625);
FORCEADD TAP..1
(1250 2725);
FORCEPROP 3 LASTPIN (1200 2725) SIG_NAME M_D_CPU1_SB_DQS_DN<6>
J 0
(1210 2735);
DISPLAY 0.659574 (1210 2735);
PAINT MONO (1210 2735);
DISPLAY INVISIBLE (1210 2735);
FORCEPROP 1 LASTPIN (1200 2725) BN 6
J 0
(1188 2733);
DISPLAY 0.680851 (1188 2733);
PAINT GREEN (1188 2733);
FORCEPROP 2 LAST CDS_LIB standard
J 0
(1250 2725);
DISPLAY INVISIBLE (1250 2725);
FORCEPROP 1 LAST BODY_TYPE PLUMBING
J 0
(1250 2775);
DISPLAY 0.872340 (1250 2775);
PAINT GREEN (1250 2775);
DISPLAY INVISIBLE (1250 2775);
FORCEPROP 1 LAST HDL_TAP TRUE
J 0
(1575 2600);
DISPLAY 0.872340 (1575 2600);
DISPLAY INVISIBLE (1575 2600);
FORCEPROP 1 LAST PATH I146
J 0
(1248 2725);
DISPLAY 0.872340 (1248 2725);
PAINT GREEN (1248 2725);
DISPLAY INVISIBLE (1248 2725);
FORCEADD TAP..1
(1250 2825);
FORCEPROP 3 LASTPIN (1200 2825) SIG_NAME M_D_CPU1_SB_DQS_DN<7>
J 0
(1210 2835);
DISPLAY 0.659574 (1210 2835);
PAINT MONO (1210 2835);
DISPLAY INVISIBLE (1210 2835);
FORCEPROP 1 LASTPIN (1200 2825) BN 7
J 0
(1188 2833);
DISPLAY 0.680851 (1188 2833);
PAINT GREEN (1188 2833);
FORCEPROP 2 LAST CDS_LIB standard
J 0
(1250 2825);
DISPLAY INVISIBLE (1250 2825);
FORCEPROP 1 LAST BODY_TYPE PLUMBING
J 0
(1250 2875);
DISPLAY 0.872340 (1250 2875);
PAINT GREEN (1250 2875);
DISPLAY INVISIBLE (1250 2875);
FORCEPROP 1 LAST HDL_TAP TRUE
J 0
(1575 2700);
DISPLAY 0.872340 (1575 2700);
DISPLAY INVISIBLE (1575 2700);
FORCEPROP 1 LAST PATH I147
J 0
(1248 2825);
DISPLAY 0.872340 (1248 2825);
PAINT GREEN (1248 2825);
DISPLAY INVISIBLE (1248 2825);
FORCEADD TAP..1
(1250 2925);
FORCEPROP 3 LASTPIN (1200 2925) SIG_NAME M_D_CPU1_SB_DQS_DN<8>
J 0
(1210 2935);
DISPLAY 0.659574 (1210 2935);
PAINT MONO (1210 2935);
DISPLAY INVISIBLE (1210 2935);
FORCEPROP 1 LASTPIN (1200 2925) BN 8
J 0
(1188 2933);
DISPLAY 0.680851 (1188 2933);
PAINT GREEN (1188 2933);
FORCEPROP 2 LAST CDS_LIB standard
J 0
(1250 2925);
DISPLAY INVISIBLE (1250 2925);
FORCEPROP 1 LAST BODY_TYPE PLUMBING
J 0
(1250 2975);
DISPLAY 0.872340 (1250 2975);
PAINT GREEN (1250 2975);
DISPLAY INVISIBLE (1250 2975);
FORCEPROP 1 LAST HDL_TAP TRUE
J 0
(1575 2800);
DISPLAY 0.872340 (1575 2800);
DISPLAY INVISIBLE (1575 2800);
FORCEPROP 1 LAST PATH I148
J 0
(1248 2925);
DISPLAY 0.872340 (1248 2925);
PAINT GREEN (1248 2925);
DISPLAY INVISIBLE (1248 2925);
FORCEADD TAP..1
(1250 3025);
FORCEPROP 3 LASTPIN (1200 3025) SIG_NAME M_D_CPU1_SB_DQS_DN<9>
J 0
(1210 3035);
DISPLAY 0.659574 (1210 3035);
PAINT MONO (1210 3035);
DISPLAY INVISIBLE (1210 3035);
FORCEPROP 1 LASTPIN (1200 3025) BN 9
J 0
(1188 3033);
DISPLAY 0.680851 (1188 3033);
PAINT GREEN (1188 3033);
FORCEPROP 2 LAST CDS_LIB standard
J 0
(1250 3025);
DISPLAY INVISIBLE (1250 3025);
FORCEPROP 1 LAST BODY_TYPE PLUMBING
J 0
(1250 3075);
DISPLAY 0.872340 (1250 3075);
PAINT GREEN (1250 3075);
DISPLAY INVISIBLE (1250 3075);
FORCEPROP 1 LAST HDL_TAP TRUE
J 0
(1575 2900);
DISPLAY 0.872340 (1575 2900);
DISPLAY INVISIBLE (1575 2900);
FORCEPROP 1 LAST PATH I149
J 0
(1248 3025);
DISPLAY 0.872340 (1248 3025);
PAINT GREEN (1248 3025);
DISPLAY INVISIBLE (1248 3025);
FORCEADD OFFPAGE..3
R 2
(-4250 2750);
FORCEPROP 2 LAST $XR1 105 
J 0
(-4619 2750);
DISPLAY 0.638298 (-4619 2750);
PAINT MONO (-4619 2750);
FORCEPROP 2 LAST $XR0 54 
J 0
(-4499 2750);
DISPLAY 0.638298 (-4499 2750);
PAINT MONO (-4499 2750);
FORCEPROP 2 LAST CDS_LIB standard
J 0
(-4250 2750);
PAINT MONO (-4250 2750);
DISPLAY INVISIBLE (-4250 2750);
FORCEPROP 1 LAST OFFPAGE TRUE
J 2
(-4575 2625);
DISPLAY 0.872340 (-4575 2625);
DISPLAY INVISIBLE (-4575 2625);
FORCEPROP 1 LAST COMMENT_BODY TRUE
J 2
(-4200 2650);
DISPLAY 0.872340 (-4200 2650);
PAINT GREEN (-4200 2650);
DISPLAY INVISIBLE (-4200 2650);
FORCEPROP 2 LAST PATH I15
J 0
(-4200 2825);
DISPLAY 1.021277 (-4200 2825);
DISPLAY INVISIBLE (-4200 2825);
FORCEADD TAP..1
(1075 3225);
FORCEPROP 3 LASTPIN (1025 3225) SIG_NAME M_D_CPU1_SA_DQS_DP<0>
J 0
(1035 3235);
DISPLAY 0.659574 (1035 3235);
PAINT MONO (1035 3235);
DISPLAY INVISIBLE (1035 3235);
FORCEPROP 1 LASTPIN (1025 3225) BN 0
J 0
(1013 3233);
DISPLAY 0.680851 (1013 3233);
PAINT GREEN (1013 3233);
FORCEPROP 2 LAST CDS_LIB standard
J 0
(1075 3225);
PAINT MONO (1075 3225);
DISPLAY INVISIBLE (1075 3225);
FORCEPROP 1 LAST BODY_TYPE PLUMBING
J 0
(1075 3275);
DISPLAY 0.872340 (1075 3275);
PAINT GREEN (1075 3275);
DISPLAY INVISIBLE (1075 3275);
FORCEPROP 1 LAST HDL_TAP TRUE
J 0
(1400 3100);
DISPLAY 0.872340 (1400 3100);
DISPLAY INVISIBLE (1400 3100);
FORCEPROP 1 LAST PATH I150
J 0
(1073 3225);
DISPLAY 0.872340 (1073 3225);
PAINT GREEN (1073 3225);
DISPLAY INVISIBLE (1073 3225);
FORCEADD TAP..1
(1075 3325);
FORCEPROP 3 LASTPIN (1025 3325) SIG_NAME M_D_CPU1_SA_DQS_DP<1>
J 0
(1035 3335);
DISPLAY 0.659574 (1035 3335);
PAINT MONO (1035 3335);
DISPLAY INVISIBLE (1035 3335);
FORCEPROP 1 LASTPIN (1025 3325) BN 1
J 0
(1013 3333);
DISPLAY 0.680851 (1013 3333);
PAINT GREEN (1013 3333);
FORCEPROP 2 LAST CDS_LIB standard
J 0
(1075 3325);
DISPLAY INVISIBLE (1075 3325);
FORCEPROP 1 LAST BODY_TYPE PLUMBING
J 0
(1075 3375);
DISPLAY 0.872340 (1075 3375);
PAINT GREEN (1075 3375);
DISPLAY INVISIBLE (1075 3375);
FORCEPROP 1 LAST HDL_TAP TRUE
J 0
(1400 3200);
DISPLAY 0.872340 (1400 3200);
DISPLAY INVISIBLE (1400 3200);
FORCEPROP 1 LAST PATH I151
J 0
(1073 3325);
DISPLAY 0.872340 (1073 3325);
PAINT GREEN (1073 3325);
DISPLAY INVISIBLE (1073 3325);
FORCEADD TAP..1
(1075 3425);
FORCEPROP 3 LASTPIN (1025 3425) SIG_NAME M_D_CPU1_SA_DQS_DP<2>
J 0
(1035 3435);
DISPLAY 0.659574 (1035 3435);
PAINT MONO (1035 3435);
DISPLAY INVISIBLE (1035 3435);
FORCEPROP 1 LASTPIN (1025 3425) BN 2
J 0
(1013 3433);
DISPLAY 0.680851 (1013 3433);
PAINT GREEN (1013 3433);
FORCEPROP 2 LAST CDS_LIB standard
J 0
(1075 3425);
DISPLAY INVISIBLE (1075 3425);
FORCEPROP 1 LAST BODY_TYPE PLUMBING
J 0
(1075 3475);
DISPLAY 0.872340 (1075 3475);
PAINT GREEN (1075 3475);
DISPLAY INVISIBLE (1075 3475);
FORCEPROP 1 LAST HDL_TAP TRUE
J 0
(1400 3300);
DISPLAY 0.872340 (1400 3300);
DISPLAY INVISIBLE (1400 3300);
FORCEPROP 1 LAST PATH I152
J 0
(1073 3425);
DISPLAY 0.872340 (1073 3425);
PAINT GREEN (1073 3425);
DISPLAY INVISIBLE (1073 3425);
FORCEADD TAP..1
(1075 3625);
FORCEPROP 3 LASTPIN (1025 3625) SIG_NAME M_D_CPU1_SA_DQS_DP<4>
J 0
(1035 3635);
DISPLAY 0.659574 (1035 3635);
PAINT MONO (1035 3635);
DISPLAY INVISIBLE (1035 3635);
FORCEPROP 1 LASTPIN (1025 3625) BN 4
J 0
(1013 3633);
DISPLAY 0.680851 (1013 3633);
PAINT GREEN (1013 3633);
FORCEPROP 2 LAST CDS_LIB standard
J 0
(1075 3625);
PAINT MONO (1075 3625);
DISPLAY INVISIBLE (1075 3625);
FORCEPROP 1 LAST BODY_TYPE PLUMBING
J 0
(1075 3675);
DISPLAY 0.872340 (1075 3675);
PAINT GREEN (1075 3675);
DISPLAY INVISIBLE (1075 3675);
FORCEPROP 1 LAST HDL_TAP TRUE
J 0
(1400 3500);
DISPLAY 0.872340 (1400 3500);
DISPLAY INVISIBLE (1400 3500);
FORCEPROP 1 LAST PATH I153
J 0
(1073 3625);
DISPLAY 0.872340 (1073 3625);
PAINT GREEN (1073 3625);
DISPLAY INVISIBLE (1073 3625);
FORCEADD TAP..1
(1075 3525);
FORCEPROP 3 LASTPIN (1025 3525) SIG_NAME M_D_CPU1_SA_DQS_DP<3>
J 0
(1035 3535);
DISPLAY 0.659574 (1035 3535);
PAINT MONO (1035 3535);
DISPLAY INVISIBLE (1035 3535);
FORCEPROP 1 LASTPIN (1025 3525) BN 3
J 0
(1013 3533);
DISPLAY 0.680851 (1013 3533);
PAINT GREEN (1013 3533);
FORCEPROP 2 LAST CDS_LIB standard
J 0
(1075 3525);
PAINT MONO (1075 3525);
DISPLAY INVISIBLE (1075 3525);
FORCEPROP 1 LAST BODY_TYPE PLUMBING
J 0
(1075 3575);
DISPLAY 0.872340 (1075 3575);
PAINT GREEN (1075 3575);
DISPLAY INVISIBLE (1075 3575);
FORCEPROP 1 LAST HDL_TAP TRUE
J 0
(1400 3400);
DISPLAY 0.872340 (1400 3400);
DISPLAY INVISIBLE (1400 3400);
FORCEPROP 1 LAST PATH I154
J 0
(1073 3525);
DISPLAY 0.872340 (1073 3525);
PAINT GREEN (1073 3525);
DISPLAY INVISIBLE (1073 3525);
FORCEADD TAP..1
(1075 3725);
FORCEPROP 3 LASTPIN (1025 3725) SIG_NAME M_D_CPU1_SA_DQS_DP<5>
J 0
(1035 3735);
DISPLAY 0.659574 (1035 3735);
PAINT MONO (1035 3735);
DISPLAY INVISIBLE (1035 3735);
FORCEPROP 1 LASTPIN (1025 3725) BN 5
J 0
(1013 3733);
DISPLAY 0.680851 (1013 3733);
PAINT GREEN (1013 3733);
FORCEPROP 2 LAST CDS_LIB standard
J 0
(1075 3725);
DISPLAY INVISIBLE (1075 3725);
FORCEPROP 1 LAST BODY_TYPE PLUMBING
J 0
(1075 3775);
DISPLAY 0.872340 (1075 3775);
PAINT GREEN (1075 3775);
DISPLAY INVISIBLE (1075 3775);
FORCEPROP 1 LAST HDL_TAP TRUE
J 0
(1400 3600);
DISPLAY 0.872340 (1400 3600);
DISPLAY INVISIBLE (1400 3600);
FORCEPROP 1 LAST PATH I155
J 0
(1073 3725);
DISPLAY 0.872340 (1073 3725);
PAINT GREEN (1073 3725);
DISPLAY INVISIBLE (1073 3725);
FORCEADD TAP..1
(1075 3825);
FORCEPROP 3 LASTPIN (1025 3825) SIG_NAME M_D_CPU1_SA_DQS_DP<6>
J 0
(1035 3835);
DISPLAY 0.659574 (1035 3835);
PAINT MONO (1035 3835);
DISPLAY INVISIBLE (1035 3835);
FORCEPROP 1 LASTPIN (1025 3825) BN 6
J 0
(1013 3833);
DISPLAY 0.680851 (1013 3833);
PAINT GREEN (1013 3833);
FORCEPROP 2 LAST CDS_LIB standard
J 0
(1075 3825);
DISPLAY INVISIBLE (1075 3825);
FORCEPROP 1 LAST BODY_TYPE PLUMBING
J 0
(1075 3875);
DISPLAY 0.872340 (1075 3875);
PAINT GREEN (1075 3875);
DISPLAY INVISIBLE (1075 3875);
FORCEPROP 1 LAST HDL_TAP TRUE
J 0
(1400 3700);
DISPLAY 0.872340 (1400 3700);
DISPLAY INVISIBLE (1400 3700);
FORCEPROP 1 LAST PATH I156
J 0
(1073 3825);
DISPLAY 0.872340 (1073 3825);
PAINT GREEN (1073 3825);
DISPLAY INVISIBLE (1073 3825);
FORCEADD TAP..1
(1075 3925);
FORCEPROP 3 LASTPIN (1025 3925) SIG_NAME M_D_CPU1_SA_DQS_DP<7>
J 0
(1035 3935);
DISPLAY 0.659574 (1035 3935);
PAINT MONO (1035 3935);
DISPLAY INVISIBLE (1035 3935);
FORCEPROP 1 LASTPIN (1025 3925) BN 7
J 0
(1013 3933);
DISPLAY 0.680851 (1013 3933);
PAINT GREEN (1013 3933);
FORCEPROP 2 LAST CDS_LIB standard
J 0
(1075 3925);
DISPLAY INVISIBLE (1075 3925);
FORCEPROP 1 LAST BODY_TYPE PLUMBING
J 0
(1075 3975);
DISPLAY 0.872340 (1075 3975);
PAINT GREEN (1075 3975);
DISPLAY INVISIBLE (1075 3975);
FORCEPROP 1 LAST HDL_TAP TRUE
J 0
(1400 3800);
DISPLAY 0.872340 (1400 3800);
DISPLAY INVISIBLE (1400 3800);
FORCEPROP 1 LAST PATH I157
J 0
(1073 3925);
DISPLAY 0.872340 (1073 3925);
PAINT GREEN (1073 3925);
DISPLAY INVISIBLE (1073 3925);
FORCEADD TAP..1
(1075 4125);
FORCEPROP 3 LASTPIN (1025 4125) SIG_NAME M_D_CPU1_SA_DQS_DP<9>
J 0
(1035 4135);
DISPLAY 0.659574 (1035 4135);
PAINT MONO (1035 4135);
DISPLAY INVISIBLE (1035 4135);
FORCEPROP 1 LASTPIN (1025 4125) BN 9
J 0
(1013 4133);
DISPLAY 0.680851 (1013 4133);
PAINT GREEN (1013 4133);
FORCEPROP 2 LAST CDS_LIB standard
J 0
(1075 4125);
DISPLAY INVISIBLE (1075 4125);
FORCEPROP 1 LAST BODY_TYPE PLUMBING
J 0
(1075 4175);
DISPLAY 0.872340 (1075 4175);
PAINT GREEN (1075 4175);
DISPLAY INVISIBLE (1075 4175);
FORCEPROP 1 LAST HDL_TAP TRUE
J 0
(1400 4000);
DISPLAY 0.872340 (1400 4000);
DISPLAY INVISIBLE (1400 4000);
FORCEPROP 1 LAST PATH I158
J 0
(1073 4125);
DISPLAY 0.872340 (1073 4125);
PAINT GREEN (1073 4125);
DISPLAY INVISIBLE (1073 4125);
FORCEADD TAP..1
(1075 4025);
FORCEPROP 3 LASTPIN (1025 4025) SIG_NAME M_D_CPU1_SA_DQS_DP<8>
J 0
(1035 4035);
DISPLAY 0.659574 (1035 4035);
PAINT MONO (1035 4035);
DISPLAY INVISIBLE (1035 4035);
FORCEPROP 1 LASTPIN (1025 4025) BN 8
J 0
(1013 4033);
DISPLAY 0.680851 (1013 4033);
PAINT GREEN (1013 4033);
FORCEPROP 2 LAST CDS_LIB standard
J 0
(1075 4025);
DISPLAY INVISIBLE (1075 4025);
FORCEPROP 1 LAST BODY_TYPE PLUMBING
J 0
(1075 4075);
DISPLAY 0.872340 (1075 4075);
PAINT GREEN (1075 4075);
DISPLAY INVISIBLE (1075 4075);
FORCEPROP 1 LAST HDL_TAP TRUE
J 0
(1400 3900);
DISPLAY 0.872340 (1400 3900);
DISPLAY INVISIBLE (1400 3900);
FORCEPROP 1 LAST PATH I159
J 0
(1073 4025);
DISPLAY 0.872340 (1073 4025);
PAINT GREEN (1073 4025);
DISPLAY INVISIBLE (1073 4025);
FORCEADD OFFPAGE..1
(-4250 2875);
FORCEPROP 2 LAST $XR0 54 
J 0
(-4471 2875);
DISPLAY 0.638298 (-4471 2875);
PAINT MONO (-4471 2875);
FORCEPROP 2 LAST CDS_LIB standard
J 0
(-4250 2875);
PAINT MONO (-4250 2875);
DISPLAY INVISIBLE (-4250 2875);
FORCEPROP 1 LAST OFFPAGE TRUE
J 0
(-3925 2750);
DISPLAY 0.872340 (-3925 2750);
DISPLAY INVISIBLE (-3925 2750);
FORCEPROP 1 LAST COMMENT_BODY TRUE
J 0
(-4125 2775);
DISPLAY 0.872340 (-4125 2775);
PAINT GREEN (-4125 2775);
DISPLAY INVISIBLE (-4125 2775);
FORCEPROP 2 LAST PATH I16
J 0
(-4200 2950);
DISPLAY 1.021277 (-4200 2950);
DISPLAY INVISIBLE (-4200 2950);
FORCEADD TAP..1
(1250 3175);
FORCEPROP 3 LASTPIN (1200 3175) SIG_NAME M_D_CPU1_SA_DQS_DN<0>
J 0
(1210 3185);
DISPLAY 0.659574 (1210 3185);
PAINT MONO (1210 3185);
DISPLAY INVISIBLE (1210 3185);
FORCEPROP 1 LASTPIN (1200 3175) BN 0
J 0
(1188 3183);
DISPLAY 0.680851 (1188 3183);
PAINT GREEN (1188 3183);
FORCEPROP 2 LAST CDS_LIB standard
J 0
(1250 3175);
PAINT MONO (1250 3175);
DISPLAY INVISIBLE (1250 3175);
FORCEPROP 1 LAST BODY_TYPE PLUMBING
J 0
(1250 3225);
DISPLAY 0.872340 (1250 3225);
PAINT GREEN (1250 3225);
DISPLAY INVISIBLE (1250 3225);
FORCEPROP 1 LAST HDL_TAP TRUE
J 0
(1575 3050);
DISPLAY 0.872340 (1575 3050);
DISPLAY INVISIBLE (1575 3050);
FORCEPROP 1 LAST PATH I160
J 0
(1248 3175);
DISPLAY 0.872340 (1248 3175);
PAINT GREEN (1248 3175);
DISPLAY INVISIBLE (1248 3175);
FORCEADD TAP..1
(1250 3275);
FORCEPROP 3 LASTPIN (1200 3275) SIG_NAME M_D_CPU1_SA_DQS_DN<1>
J 0
(1210 3285);
DISPLAY 0.659574 (1210 3285);
PAINT MONO (1210 3285);
DISPLAY INVISIBLE (1210 3285);
FORCEPROP 1 LASTPIN (1200 3275) BN 1
J 0
(1188 3283);
DISPLAY 0.680851 (1188 3283);
PAINT GREEN (1188 3283);
FORCEPROP 2 LAST CDS_LIB standard
J 0
(1250 3275);
DISPLAY INVISIBLE (1250 3275);
FORCEPROP 1 LAST BODY_TYPE PLUMBING
J 0
(1250 3325);
DISPLAY 0.872340 (1250 3325);
PAINT GREEN (1250 3325);
DISPLAY INVISIBLE (1250 3325);
FORCEPROP 1 LAST HDL_TAP TRUE
J 0
(1575 3150);
DISPLAY 0.872340 (1575 3150);
DISPLAY INVISIBLE (1575 3150);
FORCEPROP 1 LAST PATH I161
J 0
(1248 3275);
DISPLAY 0.872340 (1248 3275);
PAINT GREEN (1248 3275);
DISPLAY INVISIBLE (1248 3275);
FORCEADD TAP..1
(1250 3375);
FORCEPROP 3 LASTPIN (1200 3375) SIG_NAME M_D_CPU1_SA_DQS_DN<2>
J 0
(1210 3385);
DISPLAY 0.659574 (1210 3385);
PAINT MONO (1210 3385);
DISPLAY INVISIBLE (1210 3385);
FORCEPROP 1 LASTPIN (1200 3375) BN 2
J 0
(1188 3383);
DISPLAY 0.680851 (1188 3383);
PAINT GREEN (1188 3383);
FORCEPROP 2 LAST CDS_LIB standard
J 0
(1250 3375);
DISPLAY INVISIBLE (1250 3375);
FORCEPROP 1 LAST BODY_TYPE PLUMBING
J 0
(1250 3425);
DISPLAY 0.872340 (1250 3425);
PAINT GREEN (1250 3425);
DISPLAY INVISIBLE (1250 3425);
FORCEPROP 1 LAST HDL_TAP TRUE
J 0
(1575 3250);
DISPLAY 0.872340 (1575 3250);
DISPLAY INVISIBLE (1575 3250);
FORCEPROP 1 LAST PATH I162
J 0
(1248 3375);
DISPLAY 0.872340 (1248 3375);
PAINT GREEN (1248 3375);
DISPLAY INVISIBLE (1248 3375);
FORCEADD TAP..1
(1250 3475);
FORCEPROP 3 LASTPIN (1200 3475) SIG_NAME M_D_CPU1_SA_DQS_DN<3>
J 0
(1210 3485);
DISPLAY 0.659574 (1210 3485);
PAINT MONO (1210 3485);
DISPLAY INVISIBLE (1210 3485);
FORCEPROP 1 LASTPIN (1200 3475) BN 3
J 0
(1188 3483);
DISPLAY 0.680851 (1188 3483);
PAINT GREEN (1188 3483);
FORCEPROP 2 LAST CDS_LIB standard
J 0
(1250 3475);
PAINT MONO (1250 3475);
DISPLAY INVISIBLE (1250 3475);
FORCEPROP 1 LAST BODY_TYPE PLUMBING
J 0
(1250 3525);
DISPLAY 0.872340 (1250 3525);
PAINT GREEN (1250 3525);
DISPLAY INVISIBLE (1250 3525);
FORCEPROP 1 LAST HDL_TAP TRUE
J 0
(1575 3350);
DISPLAY 0.872340 (1575 3350);
DISPLAY INVISIBLE (1575 3350);
FORCEPROP 1 LAST PATH I163
J 0
(1248 3475);
DISPLAY 0.872340 (1248 3475);
PAINT GREEN (1248 3475);
DISPLAY INVISIBLE (1248 3475);
FORCEADD TAP..1
(1250 3575);
FORCEPROP 3 LASTPIN (1200 3575) SIG_NAME M_D_CPU1_SA_DQS_DN<4>
J 0
(1210 3585);
DISPLAY 0.659574 (1210 3585);
PAINT MONO (1210 3585);
DISPLAY INVISIBLE (1210 3585);
FORCEPROP 1 LASTPIN (1200 3575) BN 4
J 0
(1188 3583);
DISPLAY 0.680851 (1188 3583);
PAINT GREEN (1188 3583);
FORCEPROP 2 LAST CDS_LIB standard
J 0
(1250 3575);
PAINT MONO (1250 3575);
DISPLAY INVISIBLE (1250 3575);
FORCEPROP 1 LAST BODY_TYPE PLUMBING
J 0
(1250 3625);
DISPLAY 0.872340 (1250 3625);
PAINT GREEN (1250 3625);
DISPLAY INVISIBLE (1250 3625);
FORCEPROP 1 LAST HDL_TAP TRUE
J 0
(1575 3450);
DISPLAY 0.872340 (1575 3450);
DISPLAY INVISIBLE (1575 3450);
FORCEPROP 1 LAST PATH I164
J 0
(1248 3575);
DISPLAY 0.872340 (1248 3575);
PAINT GREEN (1248 3575);
DISPLAY INVISIBLE (1248 3575);
FORCEADD TAP..1
(1250 3675);
FORCEPROP 3 LASTPIN (1200 3675) SIG_NAME M_D_CPU1_SA_DQS_DN<5>
J 0
(1210 3685);
DISPLAY 0.659574 (1210 3685);
PAINT MONO (1210 3685);
DISPLAY INVISIBLE (1210 3685);
FORCEPROP 1 LASTPIN (1200 3675) BN 5
J 0
(1188 3683);
DISPLAY 0.680851 (1188 3683);
PAINT GREEN (1188 3683);
FORCEPROP 2 LAST CDS_LIB standard
J 0
(1250 3675);
DISPLAY INVISIBLE (1250 3675);
FORCEPROP 1 LAST BODY_TYPE PLUMBING
J 0
(1250 3725);
DISPLAY 0.872340 (1250 3725);
PAINT GREEN (1250 3725);
DISPLAY INVISIBLE (1250 3725);
FORCEPROP 1 LAST HDL_TAP TRUE
J 0
(1575 3550);
DISPLAY 0.872340 (1575 3550);
DISPLAY INVISIBLE (1575 3550);
FORCEPROP 1 LAST PATH I165
J 0
(1248 3675);
DISPLAY 0.872340 (1248 3675);
PAINT GREEN (1248 3675);
DISPLAY INVISIBLE (1248 3675);
FORCEADD TAP..1
(1250 3775);
FORCEPROP 3 LASTPIN (1200 3775) SIG_NAME M_D_CPU1_SA_DQS_DN<6>
J 0
(1210 3785);
DISPLAY 0.659574 (1210 3785);
PAINT MONO (1210 3785);
DISPLAY INVISIBLE (1210 3785);
FORCEPROP 1 LASTPIN (1200 3775) BN 6
J 0
(1188 3783);
DISPLAY 0.680851 (1188 3783);
PAINT GREEN (1188 3783);
FORCEPROP 2 LAST CDS_LIB standard
J 0
(1250 3775);
DISPLAY INVISIBLE (1250 3775);
FORCEPROP 1 LAST BODY_TYPE PLUMBING
J 0
(1250 3825);
DISPLAY 0.872340 (1250 3825);
PAINT GREEN (1250 3825);
DISPLAY INVISIBLE (1250 3825);
FORCEPROP 1 LAST HDL_TAP TRUE
J 0
(1575 3650);
DISPLAY 0.872340 (1575 3650);
DISPLAY INVISIBLE (1575 3650);
FORCEPROP 1 LAST PATH I166
J 0
(1248 3775);
DISPLAY 0.872340 (1248 3775);
PAINT GREEN (1248 3775);
DISPLAY INVISIBLE (1248 3775);
FORCEADD TAP..1
(1250 3875);
FORCEPROP 3 LASTPIN (1200 3875) SIG_NAME M_D_CPU1_SA_DQS_DN<7>
J 0
(1210 3885);
DISPLAY 0.659574 (1210 3885);
PAINT MONO (1210 3885);
DISPLAY INVISIBLE (1210 3885);
FORCEPROP 1 LASTPIN (1200 3875) BN 7
J 0
(1188 3883);
DISPLAY 0.680851 (1188 3883);
PAINT GREEN (1188 3883);
FORCEPROP 2 LAST CDS_LIB standard
J 0
(1250 3875);
DISPLAY INVISIBLE (1250 3875);
FORCEPROP 1 LAST BODY_TYPE PLUMBING
J 0
(1250 3925);
DISPLAY 0.872340 (1250 3925);
PAINT GREEN (1250 3925);
DISPLAY INVISIBLE (1250 3925);
FORCEPROP 1 LAST HDL_TAP TRUE
J 0
(1575 3750);
DISPLAY 0.872340 (1575 3750);
DISPLAY INVISIBLE (1575 3750);
FORCEPROP 1 LAST PATH I167
J 0
(1248 3875);
DISPLAY 0.872340 (1248 3875);
PAINT GREEN (1248 3875);
DISPLAY INVISIBLE (1248 3875);
FORCEADD TAP..1
(1250 3975);
FORCEPROP 3 LASTPIN (1200 3975) SIG_NAME M_D_CPU1_SA_DQS_DN<8>
J 0
(1210 3985);
DISPLAY 0.659574 (1210 3985);
PAINT MONO (1210 3985);
DISPLAY INVISIBLE (1210 3985);
FORCEPROP 1 LASTPIN (1200 3975) BN 8
J 0
(1188 3983);
DISPLAY 0.680851 (1188 3983);
PAINT GREEN (1188 3983);
FORCEPROP 2 LAST CDS_LIB standard
J 0
(1250 3975);
DISPLAY INVISIBLE (1250 3975);
FORCEPROP 1 LAST BODY_TYPE PLUMBING
J 0
(1250 4025);
DISPLAY 0.872340 (1250 4025);
PAINT GREEN (1250 4025);
DISPLAY INVISIBLE (1250 4025);
FORCEPROP 1 LAST HDL_TAP TRUE
J 0
(1575 3850);
DISPLAY 0.872340 (1575 3850);
DISPLAY INVISIBLE (1575 3850);
FORCEPROP 1 LAST PATH I168
J 0
(1248 3975);
DISPLAY 0.872340 (1248 3975);
PAINT GREEN (1248 3975);
DISPLAY INVISIBLE (1248 3975);
FORCEADD TAP..1
(1250 4075);
FORCEPROP 3 LASTPIN (1200 4075) SIG_NAME M_D_CPU1_SA_DQS_DN<9>
J 0
(1210 4085);
DISPLAY 0.659574 (1210 4085);
PAINT MONO (1210 4085);
DISPLAY INVISIBLE (1210 4085);
FORCEPROP 1 LASTPIN (1200 4075) BN 9
J 0
(1188 4083);
DISPLAY 0.680851 (1188 4083);
PAINT GREEN (1188 4083);
FORCEPROP 2 LAST CDS_LIB standard
J 0
(1250 4075);
DISPLAY INVISIBLE (1250 4075);
FORCEPROP 1 LAST BODY_TYPE PLUMBING
J 0
(1250 4125);
DISPLAY 0.872340 (1250 4125);
PAINT GREEN (1250 4125);
DISPLAY INVISIBLE (1250 4125);
FORCEPROP 1 LAST HDL_TAP TRUE
J 0
(1575 3950);
DISPLAY 0.872340 (1575 3950);
DISPLAY INVISIBLE (1575 3950);
FORCEPROP 1 LAST PATH I169
J 0
(1248 4075);
DISPLAY 0.872340 (1248 4075);
PAINT GREEN (1248 4075);
DISPLAY INVISIBLE (1248 4075);
FORCEADD OFFPAGE..1
(-4250 3025);
FORCEPROP 2 LAST $XR0 54 
J 0
(-4471 3025);
DISPLAY 0.638298 (-4471 3025);
PAINT MONO (-4471 3025);
FORCEPROP 2 LAST CDS_LIB standard
J 0
(-4250 3025);
PAINT MONO (-4250 3025);
DISPLAY INVISIBLE (-4250 3025);
FORCEPROP 1 LAST OFFPAGE TRUE
J 0
(-3925 2900);
DISPLAY 0.872340 (-3925 2900);
DISPLAY INVISIBLE (-3925 2900);
FORCEPROP 1 LAST COMMENT_BODY TRUE
J 0
(-4125 2925);
DISPLAY 0.872340 (-4125 2925);
PAINT GREEN (-4125 2925);
DISPLAY INVISIBLE (-4125 2925);
FORCEPROP 2 LAST PATH I17
J 0
(-4200 3100);
DISPLAY 1.021277 (-4200 3100);
DISPLAY INVISIBLE (-4200 3100);
FORCEADD OFFPAGE..2
(2200 3050);
FORCEPROP 2 LAST $XR1 105 
J 0
(2479 3050);
DISPLAY 0.638298 (2479 3050);
PAINT MONO (2479 3050);
FORCEPROP 2 LAST $XR0 54 
J 0
(2389 3050);
DISPLAY 0.638298 (2389 3050);
PAINT MONO (2389 3050);
FORCEPROP 2 LAST CDS_LIB standard
J 0
(2200 3050);
PAINT MONO (2200 3050);
DISPLAY INVISIBLE (2200 3050);
FORCEPROP 1 LAST OFFPAGE TRUE
J 0
(2525 2925);
DISPLAY 1.170213 (2525 2925);
PAINT GREEN (2525 2925);
DISPLAY INVISIBLE (2525 2925);
FORCEPROP 1 LAST COMMENT_BODY TRUE
J 0
(2155 2955);
DISPLAY 1.170213 (2155 2955);
PAINT GREEN (2155 2955);
DISPLAY INVISIBLE (2155 2955);
FORCEPROP 2 LAST PATH I170
J 0
(2375 3125);
DISPLAY 1.021277 (2375 3125);
DISPLAY INVISIBLE (2375 3125);
FORCEADD OFFPAGE..2
(2200 3100);
FORCEPROP 2 LAST $XR1 105 
J 0
(2479 3100);
DISPLAY 0.638298 (2479 3100);
PAINT MONO (2479 3100);
FORCEPROP 2 LAST $XR0 54 
J 0
(2389 3100);
DISPLAY 0.638298 (2389 3100);
PAINT MONO (2389 3100);
FORCEPROP 2 LAST CDS_LIB standard
J 0
(2200 3100);
PAINT MONO (2200 3100);
DISPLAY INVISIBLE (2200 3100);
FORCEPROP 1 LAST OFFPAGE TRUE
J 0
(2525 2975);
DISPLAY 1.170213 (2525 2975);
PAINT GREEN (2525 2975);
DISPLAY INVISIBLE (2525 2975);
FORCEPROP 1 LAST COMMENT_BODY TRUE
J 0
(2155 3005);
DISPLAY 1.170213 (2155 3005);
PAINT GREEN (2155 3005);
DISPLAY INVISIBLE (2155 3005);
FORCEPROP 2 LAST PATH I171
J 0
(2375 3175);
DISPLAY 1.021277 (2375 3175);
DISPLAY INVISIBLE (2375 3175);
FORCEADD OFFPAGE..2
(2200 4150);
FORCEPROP 2 LAST $XR1 105 
J 0
(2479 4150);
DISPLAY 0.638298 (2479 4150);
PAINT MONO (2479 4150);
FORCEPROP 2 LAST $XR0 54 
J 0
(2389 4150);
DISPLAY 0.638298 (2389 4150);
PAINT MONO (2389 4150);
FORCEPROP 2 LAST CDS_LIB standard
J 0
(2200 4150);
PAINT MONO (2200 4150);
DISPLAY INVISIBLE (2200 4150);
FORCEPROP 1 LAST OFFPAGE TRUE
J 0
(2525 4025);
DISPLAY 1.170213 (2525 4025);
PAINT GREEN (2525 4025);
DISPLAY INVISIBLE (2525 4025);
FORCEPROP 1 LAST COMMENT_BODY TRUE
J 0
(2155 4055);
DISPLAY 1.170213 (2155 4055);
PAINT GREEN (2155 4055);
DISPLAY INVISIBLE (2155 4055);
FORCEPROP 2 LAST PATH I172
J 0
(2375 4225);
DISPLAY 1.021277 (2375 4225);
DISPLAY INVISIBLE (2375 4225);
FORCEADD OFFPAGE..2
(2200 4100);
FORCEPROP 2 LAST $XR1 105 
J 0
(2479 4100);
DISPLAY 0.638298 (2479 4100);
PAINT MONO (2479 4100);
FORCEPROP 2 LAST $XR0 54 
J 0
(2389 4100);
DISPLAY 0.638298 (2389 4100);
PAINT MONO (2389 4100);
FORCEPROP 2 LAST CDS_LIB standard
J 0
(2200 4100);
PAINT MONO (2200 4100);
DISPLAY INVISIBLE (2200 4100);
FORCEPROP 1 LAST OFFPAGE TRUE
J 0
(2525 3975);
DISPLAY 1.170213 (2525 3975);
PAINT GREEN (2525 3975);
DISPLAY INVISIBLE (2525 3975);
FORCEPROP 1 LAST COMMENT_BODY TRUE
J 0
(2155 4005);
DISPLAY 1.170213 (2155 4005);
PAINT GREEN (2155 4005);
DISPLAY INVISIBLE (2155 4005);
FORCEPROP 2 LAST PATH I173
J 0
(2375 4175);
DISPLAY 1.021277 (2375 4175);
DISPLAY INVISIBLE (2375 4175);
FORCEADD UNIVERSAL_GND..1
(2750 425);
FORCEPROP 3 LASTPIN (2750 475) SIG_NAME GND\g
J 0
(2760 485);
DISPLAY 0.659574 (2760 485);
PAINT MONO (2760 485);
DISPLAY INVISIBLE (2760 485);
FORCEPROP 1 LAST PATH I174
J 0
(2825 425);
DISPLAY 0.872340 (2825 425);
PAINT AQUA (2825 425);
DISPLAY INVISIBLE (2825 425);
FORCEPROP 1 LAST HDL_POWER GND
J 1
(2775 350);
DISPLAY 0.872340 (2775 350);
PAINT GREEN (2775 350);
DISPLAY INVISIBLE (2775 350);
FORCEPROP 2 LAST CDS_LIB logical_power
J 0
(2750 425);
PAINT MONO (2750 425);
DISPLAY INVISIBLE (2750 425);
FORCEADD SCONN288_ADR50017P130CC..3
(3600 2500);
FORCEPROP 1 LAST PART_NUMBER DFHST8FS461
J 0
(3145 4424);
DISPLAY 0.723404 (3145 4424);
PAINT GREEN (3145 4424);
DISPLAY INVISIBLE (3145 4424);
FORCEPROP 1 LAST MATERIAL IO
J 0
(3145 4297);
DISPLAY 0.723404 (3145 4297);
PAINT GREEN (3145 4297);
FORCEPROP 2 LAST PART_TYPE SMLF
J 0
(3150 4575);
DISPLAY 1.021277 (3150 4575);
FORCEPROP 2 LAST VALUE SCONN288_ADR50017-P130CC
J 0
(3150 4525);
DISPLAY 1.021277 (3150 4525);
FORCEPROP 1 LAST $LOCATION J23
J 0
(3150 4475);
DISPLAY 0.723404 (3150 4475);
PAINT GREEN (3150 4475);
FORCEPROP 0 LASTPIN (4200 875) $PN G1
J 0
(4210 885);
DISPLAY 0.680851 (4210 885);
PAINT MONO (4210 885);
FORCEPROP 0 LASTPIN (4200 825) $PN G2
J 0
(4210 835);
DISPLAY 0.680851 (4210 835);
PAINT MONO (4210 835);
FORCEPROP 0 LASTPIN (4200 775) $PN G3
J 0
(4210 785);
DISPLAY 0.680851 (4210 785);
PAINT MONO (4210 785);
FORCEPROP 0 LASTPIN (3000 4025) $PN 1
J 2
(2990 4035);
DISPLAY 0.680851 (2990 4035);
PAINT MONO (2990 4035);
FORCEPROP 0 LASTPIN (3000 4075) $PN 145
J 2
(2990 4085);
DISPLAY 0.680851 (2990 4085);
PAINT MONO (2990 4085);
FORCEPROP 0 LASTPIN (3000 4125) $PN 146
J 2
(2990 4135);
DISPLAY 0.680851 (2990 4135);
PAINT MONO (2990 4135);
FORCEPROP 0 LASTPIN (4200 975) $PN 6
J 0
(4210 985);
DISPLAY 0.680851 (4210 985);
PAINT MONO (4210 985);
FORCEPROP 0 LASTPIN (4200 1025) $PN 8
J 0
(4210 1035);
DISPLAY 0.680851 (4210 1035);
PAINT MONO (4210 1035);
FORCEPROP 0 LASTPIN (4200 1075) $PN 10
J 0
(4210 1085);
DISPLAY 0.680851 (4210 1085);
PAINT MONO (4210 1085);
FORCEPROP 0 LASTPIN (4200 1125) $PN 13
J 0
(4210 1135);
DISPLAY 0.680851 (4210 1135);
PAINT MONO (4210 1135);
FORCEPROP 0 LASTPIN (4200 1175) $PN 15
J 0
(4210 1185);
DISPLAY 0.680851 (4210 1185);
PAINT MONO (4210 1185);
FORCEPROP 0 LASTPIN (4200 1225) $PN 17
J 0
(4210 1235);
DISPLAY 0.680851 (4210 1235);
PAINT MONO (4210 1235);
FORCEPROP 0 LASTPIN (4200 1275) $PN 19
J 0
(4210 1285);
DISPLAY 0.680851 (4210 1285);
PAINT MONO (4210 1285);
FORCEPROP 0 LASTPIN (4200 1325) $PN 21
J 0
(4210 1335);
DISPLAY 0.680851 (4210 1335);
PAINT MONO (4210 1335);
FORCEPROP 0 LASTPIN (4200 1375) $PN 24
J 0
(4210 1385);
DISPLAY 0.680851 (4210 1385);
PAINT MONO (4210 1385);
FORCEPROP 0 LASTPIN (4200 1425) $PN 26
J 0
(4210 1435);
DISPLAY 0.680851 (4210 1435);
PAINT MONO (4210 1435);
FORCEPROP 0 LASTPIN (4200 1475) $PN 28
J 0
(4210 1485);
DISPLAY 0.680851 (4210 1485);
PAINT MONO (4210 1485);
FORCEPROP 0 LASTPIN (4200 1525) $PN 30
J 0
(4210 1535);
DISPLAY 0.680851 (4210 1535);
PAINT MONO (4210 1535);
FORCEPROP 0 LASTPIN (4200 1575) $PN 32
J 0
(4210 1585);
DISPLAY 0.680851 (4210 1585);
PAINT MONO (4210 1585);
FORCEPROP 0 LASTPIN (4200 1625) $PN 35
J 0
(4210 1635);
DISPLAY 0.680851 (4210 1635);
PAINT MONO (4210 1635);
FORCEPROP 0 LASTPIN (4200 1675) $PN 37
J 0
(4210 1685);
DISPLAY 0.680851 (4210 1685);
PAINT MONO (4210 1685);
FORCEPROP 0 LASTPIN (4200 1725) $PN 39
J 0
(4210 1735);
DISPLAY 0.680851 (4210 1735);
PAINT MONO (4210 1735);
FORCEPROP 0 LASTPIN (4200 1775) $PN 41
J 0
(4210 1785);
DISPLAY 0.680851 (4210 1785);
PAINT MONO (4210 1785);
FORCEPROP 0 LASTPIN (4200 1825) $PN 43
J 0
(4210 1835);
DISPLAY 0.680851 (4210 1835);
PAINT MONO (4210 1835);
FORCEPROP 0 LASTPIN (4200 1875) $PN 46
J 0
(4210 1885);
DISPLAY 0.680851 (4210 1885);
PAINT MONO (4210 1885);
FORCEPROP 0 LASTPIN (4200 1925) $PN 48
J 0
(4210 1935);
DISPLAY 0.680851 (4210 1935);
PAINT MONO (4210 1935);
FORCEPROP 0 LASTPIN (4200 1975) $PN 50
J 0
(4210 1985);
DISPLAY 0.680851 (4210 1985);
PAINT MONO (4210 1985);
FORCEPROP 0 LASTPIN (4200 2025) $PN 52
J 0
(4210 2035);
DISPLAY 0.680851 (4210 2035);
PAINT MONO (4210 2035);
FORCEPROP 0 LASTPIN (4200 2075) $PN 54
J 0
(4210 2085);
DISPLAY 0.680851 (4210 2085);
PAINT MONO (4210 2085);
FORCEPROP 0 LASTPIN (4200 2125) $PN 57
J 0
(4210 2135);
DISPLAY 0.680851 (4210 2135);
PAINT MONO (4210 2135);
FORCEPROP 0 LASTPIN (4200 2175) $PN 59
J 0
(4210 2185);
DISPLAY 0.680851 (4210 2185);
PAINT MONO (4210 2185);
FORCEPROP 0 LASTPIN (4200 2225) $PN 61
J 0
(4210 2235);
DISPLAY 0.680851 (4210 2235);
PAINT MONO (4210 2235);
FORCEPROP 0 LASTPIN (4200 2275) $PN 63
J 0
(4210 2285);
DISPLAY 0.680851 (4210 2285);
PAINT MONO (4210 2285);
FORCEPROP 0 LASTPIN (4200 2325) $PN 65
J 0
(4210 2335);
DISPLAY 0.680851 (4210 2335);
PAINT MONO (4210 2335);
FORCEPROP 0 LASTPIN (4200 2375) $PN 67
J 0
(4210 2385);
DISPLAY 0.680851 (4210 2385);
PAINT MONO (4210 2385);
FORCEPROP 0 LASTPIN (4200 2425) $PN 69
J 0
(4210 2435);
DISPLAY 0.680851 (4210 2435);
PAINT MONO (4210 2435);
FORCEPROP 0 LASTPIN (4200 2475) $PN 71
J 0
(4210 2485);
DISPLAY 0.680851 (4210 2485);
PAINT MONO (4210 2485);
FORCEPROP 0 LASTPIN (4200 2525) $PN 73
J 0
(4210 2535);
DISPLAY 0.680851 (4210 2535);
PAINT MONO (4210 2535);
FORCEPROP 0 LASTPIN (4200 2575) $PN 75
J 0
(4210 2585);
DISPLAY 0.680851 (4210 2585);
PAINT MONO (4210 2585);
FORCEPROP 0 LASTPIN (4200 2625) $PN 77
J 0
(4210 2635);
DISPLAY 0.680851 (4210 2635);
PAINT MONO (4210 2635);
FORCEPROP 0 LASTPIN (4200 2675) $PN 79
J 0
(4210 2685);
DISPLAY 0.680851 (4210 2685);
PAINT MONO (4210 2685);
FORCEPROP 0 LASTPIN (4200 2725) $PN 81
J 0
(4210 2735);
DISPLAY 0.680851 (4210 2735);
PAINT MONO (4210 2735);
FORCEPROP 0 LASTPIN (4200 2775) $PN 83
J 0
(4210 2785);
DISPLAY 0.680851 (4210 2785);
PAINT MONO (4210 2785);
FORCEPROP 0 LASTPIN (4200 2825) $PN 85
J 0
(4210 2835);
DISPLAY 0.680851 (4210 2835);
PAINT MONO (4210 2835);
FORCEPROP 0 LASTPIN (4200 2875) $PN 88
J 0
(4210 2885);
DISPLAY 0.680851 (4210 2885);
PAINT MONO (4210 2885);
FORCEPROP 0 LASTPIN (4200 2925) $PN 90
J 0
(4210 2935);
DISPLAY 0.680851 (4210 2935);
PAINT MONO (4210 2935);
FORCEPROP 0 LASTPIN (4200 2975) $PN 92
J 0
(4210 2985);
DISPLAY 0.680851 (4210 2985);
PAINT MONO (4210 2985);
FORCEPROP 0 LASTPIN (4200 3025) $PN 95
J 0
(4210 3035);
DISPLAY 0.680851 (4210 3035);
PAINT MONO (4210 3035);
FORCEPROP 0 LASTPIN (4200 3075) $PN 97
J 0
(4210 3085);
DISPLAY 0.680851 (4210 3085);
PAINT MONO (4210 3085);
FORCEPROP 0 LASTPIN (4200 3125) $PN 99
J 0
(4210 3135);
DISPLAY 0.680851 (4210 3135);
PAINT MONO (4210 3135);
FORCEPROP 0 LASTPIN (4200 3175) $PN 101
J 0
(4210 3185);
DISPLAY 0.680851 (4210 3185);
PAINT MONO (4210 3185);
FORCEPROP 0 LASTPIN (4200 3225) $PN 103
J 0
(4210 3235);
DISPLAY 0.680851 (4210 3235);
PAINT MONO (4210 3235);
FORCEPROP 0 LASTPIN (4200 3275) $PN 106
J 0
(4210 3285);
DISPLAY 0.680851 (4210 3285);
PAINT MONO (4210 3285);
FORCEPROP 0 LASTPIN (4200 3325) $PN 108
J 0
(4210 3335);
DISPLAY 0.680851 (4210 3335);
PAINT MONO (4210 3335);
FORCEPROP 0 LASTPIN (4200 3375) $PN 110
J 0
(4210 3385);
DISPLAY 0.680851 (4210 3385);
PAINT MONO (4210 3385);
FORCEPROP 0 LASTPIN (4200 3425) $PN 112
J 0
(4210 3435);
DISPLAY 0.680851 (4210 3435);
PAINT MONO (4210 3435);
FORCEPROP 0 LASTPIN (4200 3475) $PN 114
J 0
(4210 3485);
DISPLAY 0.680851 (4210 3485);
PAINT MONO (4210 3485);
FORCEPROP 0 LASTPIN (4200 3525) $PN 117
J 0
(4210 3535);
DISPLAY 0.680851 (4210 3535);
PAINT MONO (4210 3535);
FORCEPROP 0 LASTPIN (4200 3575) $PN 119
J 0
(4210 3585);
DISPLAY 0.680851 (4210 3585);
PAINT MONO (4210 3585);
FORCEPROP 0 LASTPIN (4200 3625) $PN 121
J 0
(4210 3635);
DISPLAY 0.680851 (4210 3635);
PAINT MONO (4210 3635);
FORCEPROP 0 LASTPIN (4200 3675) $PN 123
J 0
(4210 3685);
DISPLAY 0.680851 (4210 3685);
PAINT MONO (4210 3685);
FORCEPROP 0 LASTPIN (4200 3725) $PN 125
J 0
(4210 3735);
DISPLAY 0.680851 (4210 3735);
PAINT MONO (4210 3735);
FORCEPROP 0 LASTPIN (4200 3775) $PN 128
J 0
(4210 3785);
DISPLAY 0.680851 (4210 3785);
PAINT MONO (4210 3785);
FORCEPROP 0 LASTPIN (4200 3825) $PN 130
J 0
(4210 3835);
DISPLAY 0.680851 (4210 3835);
PAINT MONO (4210 3835);
FORCEPROP 0 LASTPIN (4200 3875) $PN 132
J 0
(4210 3885);
DISPLAY 0.680851 (4210 3885);
PAINT MONO (4210 3885);
FORCEPROP 0 LASTPIN (4200 3925) $PN 134
J 0
(4210 3935);
DISPLAY 0.680851 (4210 3935);
PAINT MONO (4210 3935);
FORCEPROP 0 LASTPIN (4200 3975) $PN 136
J 0
(4210 3985);
DISPLAY 0.680851 (4210 3985);
PAINT MONO (4210 3985);
FORCEPROP 0 LASTPIN (4200 4025) $PN 139
J 0
(4210 4035);
DISPLAY 0.680851 (4210 4035);
PAINT MONO (4210 4035);
FORCEPROP 0 LASTPIN (4200 4075) $PN 141
J 0
(4210 4085);
DISPLAY 0.680851 (4210 4085);
PAINT MONO (4210 4085);
FORCEPROP 0 LASTPIN (4200 4125) $PN 143
J 0
(4210 4135);
DISPLAY 0.680851 (4210 4135);
PAINT MONO (4210 4135);
FORCEPROP 0 LASTPIN (3000 875) $PN 151
J 2
(2990 885);
DISPLAY 0.680851 (2990 885);
PAINT MONO (2990 885);
FORCEPROP 0 LASTPIN (3000 925) $PN 153
J 2
(2990 935);
DISPLAY 0.680851 (2990 935);
PAINT MONO (2990 935);
FORCEPROP 0 LASTPIN (3000 975) $PN 155
J 2
(2990 985);
DISPLAY 0.680851 (2990 985);
PAINT MONO (2990 985);
FORCEPROP 0 LASTPIN (3000 1025) $PN 158
J 2
(2990 1035);
DISPLAY 0.680851 (2990 1035);
PAINT MONO (2990 1035);
FORCEPROP 0 LASTPIN (3000 1075) $PN 160
J 2
(2990 1085);
DISPLAY 0.680851 (2990 1085);
PAINT MONO (2990 1085);
FORCEPROP 0 LASTPIN (3000 1125) $PN 162
J 2
(2990 1135);
DISPLAY 0.680851 (2990 1135);
PAINT MONO (2990 1135);
FORCEPROP 0 LASTPIN (3000 1175) $PN 164
J 2
(2990 1185);
DISPLAY 0.680851 (2990 1185);
PAINT MONO (2990 1185);
FORCEPROP 0 LASTPIN (3000 1225) $PN 166
J 2
(2990 1235);
DISPLAY 0.680851 (2990 1235);
PAINT MONO (2990 1235);
FORCEPROP 0 LASTPIN (3000 1275) $PN 169
J 2
(2990 1285);
DISPLAY 0.680851 (2990 1285);
PAINT MONO (2990 1285);
FORCEPROP 0 LASTPIN (3000 1325) $PN 171
J 2
(2990 1335);
DISPLAY 0.680851 (2990 1335);
PAINT MONO (2990 1335);
FORCEPROP 0 LASTPIN (3000 1375) $PN 173
J 2
(2990 1385);
DISPLAY 0.680851 (2990 1385);
PAINT MONO (2990 1385);
FORCEPROP 0 LASTPIN (3000 1425) $PN 175
J 2
(2990 1435);
DISPLAY 0.680851 (2990 1435);
PAINT MONO (2990 1435);
FORCEPROP 0 LASTPIN (3000 1475) $PN 177
J 2
(2990 1485);
DISPLAY 0.680851 (2990 1485);
PAINT MONO (2990 1485);
FORCEPROP 0 LASTPIN (3000 1525) $PN 180
J 2
(2990 1535);
DISPLAY 0.680851 (2990 1535);
PAINT MONO (2990 1535);
FORCEPROP 0 LASTPIN (3000 1575) $PN 182
J 2
(2990 1585);
DISPLAY 0.680851 (2990 1585);
PAINT MONO (2990 1585);
FORCEPROP 0 LASTPIN (3000 1625) $PN 184
J 2
(2990 1635);
DISPLAY 0.680851 (2990 1635);
PAINT MONO (2990 1635);
FORCEPROP 0 LASTPIN (3000 1675) $PN 186
J 2
(2990 1685);
DISPLAY 0.680851 (2990 1685);
PAINT MONO (2990 1685);
FORCEPROP 0 LASTPIN (3000 1725) $PN 188
J 2
(2990 1735);
DISPLAY 0.680851 (2990 1735);
PAINT MONO (2990 1735);
FORCEPROP 0 LASTPIN (3000 1775) $PN 191
J 2
(2990 1785);
DISPLAY 0.680851 (2990 1785);
PAINT MONO (2990 1785);
FORCEPROP 0 LASTPIN (3000 1825) $PN 193
J 2
(2990 1835);
DISPLAY 0.680851 (2990 1835);
PAINT MONO (2990 1835);
FORCEPROP 0 LASTPIN (3000 1875) $PN 195
J 2
(2990 1885);
DISPLAY 0.680851 (2990 1885);
PAINT MONO (2990 1885);
FORCEPROP 0 LASTPIN (3000 1925) $PN 197
J 2
(2990 1935);
DISPLAY 0.680851 (2990 1935);
PAINT MONO (2990 1935);
FORCEPROP 0 LASTPIN (3000 1975) $PN 199
J 2
(2990 1985);
DISPLAY 0.680851 (2990 1985);
PAINT MONO (2990 1985);
FORCEPROP 0 LASTPIN (3000 2025) $PN 202
J 2
(2990 2035);
DISPLAY 0.680851 (2990 2035);
PAINT MONO (2990 2035);
FORCEPROP 0 LASTPIN (3000 2075) $PN 204
J 2
(2990 2085);
DISPLAY 0.680851 (2990 2085);
PAINT MONO (2990 2085);
FORCEPROP 0 LASTPIN (3000 2125) $PN 206
J 2
(2990 2135);
DISPLAY 0.680851 (2990 2135);
PAINT MONO (2990 2135);
FORCEPROP 0 LASTPIN (3000 2175) $PN 208
J 2
(2990 2185);
DISPLAY 0.680851 (2990 2185);
PAINT MONO (2990 2185);
FORCEPROP 0 LASTPIN (3000 2225) $PN 210
J 2
(2990 2235);
DISPLAY 0.680851 (2990 2235);
PAINT MONO (2990 2235);
FORCEPROP 0 LASTPIN (3000 2275) $PN 212
J 2
(2990 2285);
DISPLAY 0.680851 (2990 2285);
PAINT MONO (2990 2285);
FORCEPROP 0 LASTPIN (3000 2325) $PN 214
J 2
(2990 2335);
DISPLAY 0.680851 (2990 2335);
PAINT MONO (2990 2335);
FORCEPROP 0 LASTPIN (3000 2375) $PN 216
J 2
(2990 2385);
DISPLAY 0.680851 (2990 2385);
PAINT MONO (2990 2385);
FORCEPROP 0 LASTPIN (3000 2425) $PN 219
J 2
(2990 2435);
DISPLAY 0.680851 (2990 2435);
PAINT MONO (2990 2435);
FORCEPROP 0 LASTPIN (3000 2475) $PN 222
J 2
(2990 2485);
DISPLAY 0.680851 (2990 2485);
PAINT MONO (2990 2485);
FORCEPROP 0 LASTPIN (3000 2525) $PN 224
J 2
(2990 2535);
DISPLAY 0.680851 (2990 2535);
PAINT MONO (2990 2535);
FORCEPROP 0 LASTPIN (3000 2575) $PN 226
J 2
(2990 2585);
DISPLAY 0.680851 (2990 2585);
PAINT MONO (2990 2585);
FORCEPROP 0 LASTPIN (3000 2625) $PN 228
J 2
(2990 2635);
DISPLAY 0.680851 (2990 2635);
PAINT MONO (2990 2635);
FORCEPROP 0 LASTPIN (3000 2675) $PN 230
J 2
(2990 2685);
DISPLAY 0.680851 (2990 2685);
PAINT MONO (2990 2685);
FORCEPROP 0 LASTPIN (3000 2725) $PN 233
J 2
(2990 2735);
DISPLAY 0.680851 (2990 2735);
PAINT MONO (2990 2735);
FORCEPROP 0 LASTPIN (3000 2775) $PN 235
J 2
(2990 2785);
DISPLAY 0.680851 (2990 2785);
PAINT MONO (2990 2785);
FORCEPROP 0 LASTPIN (3000 2825) $PN 237
J 2
(2990 2835);
DISPLAY 0.680851 (2990 2835);
PAINT MONO (2990 2835);
FORCEPROP 0 LASTPIN (3000 2875) $PN 240
J 2
(2990 2885);
DISPLAY 0.680851 (2990 2885);
PAINT MONO (2990 2885);
FORCEPROP 0 LASTPIN (3000 2925) $PN 242
J 2
(2990 2935);
DISPLAY 0.680851 (2990 2935);
PAINT MONO (2990 2935);
FORCEPROP 0 LASTPIN (3000 2975) $PN 244
J 2
(2990 2985);
DISPLAY 0.680851 (2990 2985);
PAINT MONO (2990 2985);
FORCEPROP 0 LASTPIN (3000 3025) $PN 246
J 2
(2990 3035);
DISPLAY 0.680851 (2990 3035);
PAINT MONO (2990 3035);
FORCEPROP 0 LASTPIN (3000 3075) $PN 248
J 2
(2990 3085);
DISPLAY 0.680851 (2990 3085);
PAINT MONO (2990 3085);
FORCEPROP 0 LASTPIN (3000 3125) $PN 251
J 2
(2990 3135);
DISPLAY 0.680851 (2990 3135);
PAINT MONO (2990 3135);
FORCEPROP 0 LASTPIN (3000 3175) $PN 253
J 2
(2990 3185);
DISPLAY 0.680851 (2990 3185);
PAINT MONO (2990 3185);
FORCEPROP 0 LASTPIN (3000 3225) $PN 255
J 2
(2990 3235);
DISPLAY 0.680851 (2990 3235);
PAINT MONO (2990 3235);
FORCEPROP 0 LASTPIN (3000 3275) $PN 257
J 2
(2990 3285);
DISPLAY 0.680851 (2990 3285);
PAINT MONO (2990 3285);
FORCEPROP 0 LASTPIN (3000 3325) $PN 259
J 2
(2990 3335);
DISPLAY 0.680851 (2990 3335);
PAINT MONO (2990 3335);
FORCEPROP 0 LASTPIN (3000 3375) $PN 262
J 2
(2990 3385);
DISPLAY 0.680851 (2990 3385);
PAINT MONO (2990 3385);
FORCEPROP 0 LASTPIN (3000 3425) $PN 264
J 2
(2990 3435);
DISPLAY 0.680851 (2990 3435);
PAINT MONO (2990 3435);
FORCEPROP 0 LASTPIN (3000 3475) $PN 266
J 2
(2990 3485);
DISPLAY 0.680851 (2990 3485);
PAINT MONO (2990 3485);
FORCEPROP 0 LASTPIN (3000 3525) $PN 268
J 2
(2990 3535);
DISPLAY 0.680851 (2990 3535);
PAINT MONO (2990 3535);
FORCEPROP 0 LASTPIN (3000 3575) $PN 270
J 2
(2990 3585);
DISPLAY 0.680851 (2990 3585);
PAINT MONO (2990 3585);
FORCEPROP 0 LASTPIN (3000 3625) $PN 273
J 2
(2990 3635);
DISPLAY 0.680851 (2990 3635);
PAINT MONO (2990 3635);
FORCEPROP 0 LASTPIN (3000 3675) $PN 275
J 2
(2990 3685);
DISPLAY 0.680851 (2990 3685);
PAINT MONO (2990 3685);
FORCEPROP 0 LASTPIN (3000 3725) $PN 277
J 2
(2990 3735);
DISPLAY 0.680851 (2990 3735);
PAINT MONO (2990 3735);
FORCEPROP 0 LASTPIN (3000 3775) $PN 279
J 2
(2990 3785);
DISPLAY 0.680851 (2990 3785);
PAINT MONO (2990 3785);
FORCEPROP 0 LASTPIN (3000 3825) $PN 281
J 2
(2990 3835);
DISPLAY 0.680851 (2990 3835);
PAINT MONO (2990 3835);
FORCEPROP 0 LASTPIN (3000 3875) $PN 284
J 2
(2990 3885);
DISPLAY 0.680851 (2990 3885);
PAINT MONO (2990 3885);
FORCEPROP 0 LASTPIN (3000 3925) $PN 286
J 2
(2990 3935);
DISPLAY 0.680851 (2990 3935);
PAINT MONO (2990 3935);
FORCEPROP 0 LASTPIN (3000 3975) $PN 288
J 2
(2990 3985);
DISPLAY 0.680851 (2990 3985);
PAINT MONO (2990 3985);
FORCEPROP 1 LAST NEEDS_NO_SIZE TRUE
J 0
(3600 2500);
DISPLAY 0.723404 (3600 2500);
PAINT GREEN (3600 2500);
DISPLAY INVISIBLE (3600 2500);
FORCEPROP 1 LAST CDS_LMAN_SYM_OUTLINE -450,1775,450,-1775
J 0
(3600 2500);
DISPLAY 0.468085 (3600 2500);
PAINT GREEN (3600 2500);
DISPLAY INVISIBLE (3600 2500);
FORCEPROP 2 LAST CDS_LIB pure_quanta
J 0
(3600 2500);
DISPLAY INVISIBLE (3600 2500);
FORCEPROP 1 LAST PATH I175
J 0
(3600 2500);
DISPLAY 0.723404 (3600 2500);
PAINT GREEN (3600 2500);
DISPLAY INVISIBLE (3600 2500);
FORCEPROP 2 LAST CDS_LOCATION J23
J 0
(3150 4625);
DISPLAY 1.021277 (3150 4625);
DISPLAY INVISIBLE (3150 4625);
FORCEPROP 0 LAST $SEC 3
J 0
(3150 4625);
DISPLAY 0.680851 (3150 4625);
PAINT MONO (3150 4625);
DISPLAY INVISIBLE (3150 4625);
FORCEPROP 2 LAST CDS_SEC 3
J 0
(3150 4625);
DISPLAY 1.021277 (3150 4625);
DISPLAY INVISIBLE (3150 4625);
FORCEADD UNIVERSAL_GND..1
(4450 425);
FORCEPROP 3 LASTPIN (4450 475) SIG_NAME GND\g
J 0
(4460 485);
DISPLAY 0.659574 (4460 485);
PAINT MONO (4460 485);
DISPLAY INVISIBLE (4460 485);
FORCEPROP 1 LAST PATH I176
J 0
(4525 425);
DISPLAY 0.872340 (4525 425);
PAINT AQUA (4525 425);
DISPLAY INVISIBLE (4525 425);
FORCEPROP 1 LAST HDL_POWER GND
J 1
(4475 350);
DISPLAY 0.872340 (4475 350);
PAINT GREEN (4475 350);
DISPLAY INVISIBLE (4475 350);
FORCEPROP 2 LAST CDS_LIB logical_power
J 0
(4450 425);
PAINT MONO (4450 425);
DISPLAY INVISIBLE (4450 425);
FORCEADD VCC_CORE..1
(2750 4675);
FORCEPROP 3 LASTPIN (2750 4625) SIG_NAME P12V_S3_AUX_CPU1_NVDIMM\g
J 0
(2760 4635);
DISPLAY 0.659574 (2760 4635);
PAINT MONO (2760 4635);
DISPLAY INVISIBLE (2760 4635);
FORCEPROP 1 LAST HDL_POWER P12V_S3_AUX_CPU1_NVDIMM
J 1
(2750 4725);
DISPLAY 1.148936 (2750 4725);
PAINT GREEN (2750 4725);
FORCEPROP 2 LAST CDS_LIB logical_power
J 0
(2750 4675);
PAINT MONO (2750 4675);
DISPLAY INVISIBLE (2750 4675);
FORCEPROP 1 LAST PATH I177
J 0
(2800 4700);
DISPLAY 0.872340 (2800 4700);
PAINT AQUA (2800 4700);
DISPLAY INVISIBLE (2800 4700);
FORCEADD SCONN288_ADR50017P130CC..2
(175 3125);
FORCEPROP 1 LAST PART_NUMBER DFHST8FS461
J 0
(-418 4425);
DISPLAY 0.723404 (-418 4425);
PAINT GREEN (-418 4425);
DISPLAY INVISIBLE (-418 4425);
FORCEPROP 1 LAST MATERIAL IO
J 0
(-418 4298);
DISPLAY 0.723404 (-418 4298);
PAINT GREEN (-418 4298);
FORCEPROP 2 LAST PART_TYPE SMLF
J 0
(-407 4578);
DISPLAY 1.021277 (-407 4578);
FORCEPROP 2 LAST VALUE SCONN288_ADR50017-P130CC
J 0
(-407 4528);
DISPLAY 1.021277 (-407 4528);
FORCEPROP 1 LAST LOCATION J23
J 0
(-425 4475);
DISPLAY 0.723404 (-425 4475);
PAINT GREEN (-425 4475);
FORCEPROP 0 LASTPIN (925 3175) $PN 12
J 0
(935 3185);
DISPLAY 0.680851 (935 3185);
PAINT MONO (935 3185);
FORCEPROP 0 LASTPIN (925 3225) $PN 11
J 0
(935 3235);
DISPLAY 0.680851 (935 3235);
PAINT MONO (935 3235);
FORCEPROP 0 LASTPIN (925 2125) $PN 105
J 0
(935 2135);
DISPLAY 0.680851 (935 2135);
PAINT MONO (935 2135);
FORCEPROP 0 LASTPIN (925 2175) $PN 104
J 0
(935 2185);
DISPLAY 0.680851 (935 2185);
PAINT MONO (935 2185);
FORCEPROP 0 LASTPIN (925 3275) $PN 23
J 0
(935 3285);
DISPLAY 0.680851 (935 3285);
PAINT MONO (935 3285);
FORCEPROP 0 LASTPIN (925 3325) $PN 22
J 0
(935 3335);
DISPLAY 0.680851 (935 3335);
PAINT MONO (935 3335);
FORCEPROP 0 LASTPIN (925 2225) $PN 116
J 0
(935 2235);
DISPLAY 0.680851 (935 2235);
PAINT MONO (935 2235);
FORCEPROP 0 LASTPIN (925 2275) $PN 115
J 0
(935 2285);
DISPLAY 0.680851 (935 2285);
PAINT MONO (935 2285);
FORCEPROP 0 LASTPIN (925 3375) $PN 34
J 0
(935 3385);
DISPLAY 0.680851 (935 3385);
PAINT MONO (935 3385);
FORCEPROP 0 LASTPIN (925 3425) $PN 33
J 0
(935 3435);
DISPLAY 0.680851 (935 3435);
PAINT MONO (935 3435);
FORCEPROP 0 LASTPIN (925 2325) $PN 127
J 0
(935 2335);
DISPLAY 0.680851 (935 2335);
PAINT MONO (935 2335);
FORCEPROP 0 LASTPIN (925 2375) $PN 126
J 0
(935 2385);
DISPLAY 0.680851 (935 2385);
PAINT MONO (935 2385);
FORCEPROP 0 LASTPIN (925 3475) $PN 45
J 0
(935 3485);
DISPLAY 0.680851 (935 3485);
PAINT MONO (935 3485);
FORCEPROP 0 LASTPIN (925 3525) $PN 44
J 0
(935 3535);
DISPLAY 0.680851 (935 3535);
PAINT MONO (935 3535);
FORCEPROP 0 LASTPIN (925 2425) $PN 138
J 0
(935 2435);
DISPLAY 0.680851 (935 2435);
PAINT MONO (935 2435);
FORCEPROP 0 LASTPIN (925 2475) $PN 137
J 0
(935 2485);
DISPLAY 0.680851 (935 2485);
PAINT MONO (935 2485);
FORCEPROP 0 LASTPIN (925 3575) $PN 56
J 0
(935 3585);
DISPLAY 0.680851 (935 3585);
PAINT MONO (935 3585);
FORCEPROP 0 LASTPIN (925 3625) $PN 55
J 0
(935 3635);
DISPLAY 0.680851 (935 3635);
PAINT MONO (935 3635);
FORCEPROP 0 LASTPIN (925 2525) $PN 238
J 0
(935 2535);
DISPLAY 0.680851 (935 2535);
PAINT MONO (935 2535);
FORCEPROP 0 LASTPIN (925 2575) $PN 239
J 0
(935 2585);
DISPLAY 0.680851 (935 2585);
PAINT MONO (935 2585);
FORCEPROP 0 LASTPIN (925 3675) $PN 156
J 0
(935 3685);
DISPLAY 0.680851 (935 3685);
PAINT MONO (935 3685);
FORCEPROP 0 LASTPIN (925 3725) $PN 157
J 0
(935 3735);
DISPLAY 0.680851 (935 3735);
PAINT MONO (935 3735);
FORCEPROP 0 LASTPIN (925 2625) $PN 249
J 0
(935 2635);
DISPLAY 0.680851 (935 2635);
PAINT MONO (935 2635);
FORCEPROP 0 LASTPIN (925 2675) $PN 250
J 0
(935 2685);
DISPLAY 0.680851 (935 2685);
PAINT MONO (935 2685);
FORCEPROP 0 LASTPIN (925 3775) $PN 167
J 0
(935 3785);
DISPLAY 0.680851 (935 3785);
PAINT MONO (935 3785);
FORCEPROP 0 LASTPIN (925 3825) $PN 168
J 0
(935 3835);
DISPLAY 0.680851 (935 3835);
PAINT MONO (935 3835);
FORCEPROP 0 LASTPIN (925 2725) $PN 260
J 0
(935 2735);
DISPLAY 0.680851 (935 2735);
PAINT MONO (935 2735);
FORCEPROP 0 LASTPIN (925 2775) $PN 261
J 0
(935 2785);
DISPLAY 0.680851 (935 2785);
PAINT MONO (935 2785);
FORCEPROP 0 LASTPIN (925 3875) $PN 178
J 0
(935 3885);
DISPLAY 0.680851 (935 3885);
PAINT MONO (935 3885);
FORCEPROP 0 LASTPIN (925 3925) $PN 179
J 0
(935 3935);
DISPLAY 0.680851 (935 3935);
PAINT MONO (935 3935);
FORCEPROP 0 LASTPIN (925 2825) $PN 271
J 0
(935 2835);
DISPLAY 0.680851 (935 2835);
PAINT MONO (935 2835);
FORCEPROP 0 LASTPIN (925 2875) $PN 272
J 0
(935 2885);
DISPLAY 0.680851 (935 2885);
PAINT MONO (935 2885);
FORCEPROP 0 LASTPIN (925 3975) $PN 189
J 0
(935 3985);
DISPLAY 0.680851 (935 3985);
PAINT MONO (935 3985);
FORCEPROP 0 LASTPIN (925 4025) $PN 190
J 0
(935 4035);
DISPLAY 0.680851 (935 4035);
PAINT MONO (935 4035);
FORCEPROP 0 LASTPIN (925 2925) $PN 282
J 0
(935 2935);
DISPLAY 0.680851 (935 2935);
PAINT MONO (935 2935);
FORCEPROP 0 LASTPIN (925 2975) $PN 283
J 0
(935 2985);
DISPLAY 0.680851 (935 2985);
PAINT MONO (935 2985);
FORCEPROP 0 LASTPIN (925 4075) $PN 200
J 0
(935 4085);
DISPLAY 0.680851 (935 4085);
PAINT MONO (935 4085);
FORCEPROP 0 LASTPIN (925 4125) $PN 201
J 0
(935 4135);
DISPLAY 0.680851 (935 4135);
PAINT MONO (935 4135);
FORCEPROP 0 LASTPIN (925 3025) $PN 94
J 0
(935 3035);
DISPLAY 0.680851 (935 3035);
PAINT MONO (935 3035);
FORCEPROP 0 LASTPIN (925 3075) $PN 93
J 0
(935 3085);
DISPLAY 0.680851 (935 3085);
PAINT MONO (935 3085);
FORCEPROP 1 LAST NEEDS_NO_SIZE TRUE
J 0
(175 3125);
DISPLAY 0.723404 (175 3125);
PAINT GREEN (175 3125);
DISPLAY INVISIBLE (175 3125);
FORCEPROP 1 LAST CDS_LMAN_SYM_OUTLINE -600,1150,600,-1150
J 0
(175 3125);
DISPLAY 0.468085 (175 3125);
PAINT GREEN (175 3125);
DISPLAY INVISIBLE (175 3125);
FORCEPROP 2 LAST CDS_LIB pure_quanta
J 0
(175 3125);
DISPLAY INVISIBLE (175 3125);
FORCEPROP 1 LAST PATH I178
J 0
(175 3125);
DISPLAY 0.723404 (175 3125);
PAINT GREEN (175 3125);
DISPLAY INVISIBLE (175 3125);
FORCEPROP 0 LAST $SEC 2
J 0
(-400 4650);
DISPLAY 0.680851 (-400 4650);
PAINT MONO (-400 4650);
DISPLAY INVISIBLE (-400 4650);
FORCEPROP 0 LAST CDS_SEC 2
J 0
(-400 4650);
DISPLAY 1.021277 (-400 4650);
DISPLAY INVISIBLE (-400 4650);
FORCEADD OFFPAGE..1
(-3100 1350);
FORCEPROP 2 LAST $XR7 105 
J 0
(-4132 1350);
DISPLAY 0.638298 (-4132 1350);
PAINT MONO (-4132 1350);
FORCEPROP 2 LAST $XR6 103 
J 0
(-4012 1350);
DISPLAY 0.638298 (-4012 1350);
PAINT MONO (-4012 1350);
FORCEPROP 2 LAST $XR5 102 
J 0
(-3892 1350);
DISPLAY 0.638298 (-3892 1350);
PAINT MONO (-3892 1350);
FORCEPROP 2 LAST $XR4 101 
J 0
(-3772 1350);
DISPLAY 0.638298 (-3772 1350);
PAINT MONO (-3772 1350);
FORCEPROP 2 LAST $XR3 100 
J 0
(-3652 1350);
DISPLAY 0.638298 (-3652 1350);
PAINT MONO (-3652 1350);
FORCEPROP 2 LAST $XR2 99 
J 0
(-3532 1350);
DISPLAY 0.638298 (-3532 1350);
PAINT MONO (-3532 1350);
FORCEPROP 2 LAST $XR1 98 
J 0
(-3442 1350);
DISPLAY 0.638298 (-3442 1350);
PAINT MONO (-3442 1350);
FORCEPROP 2 LAST $XR0 230 
J 0
(-3352 1350);
DISPLAY 0.638298 (-3352 1350);
PAINT MONO (-3352 1350);
FORCEPROP 2 LAST CDS_LIB standard
J 2
(-3100 1350);
DISPLAY INVISIBLE (-3100 1350);
FORCEPROP 1 LAST OFFPAGE TRUE
J 0
(-2775 1225);
DISPLAY 0.872340 (-2775 1225);
DISPLAY INVISIBLE (-2775 1225);
FORCEPROP 1 LAST COMMENT_BODY TRUE
J 0
(-2975 1250);
DISPLAY 0.872340 (-2975 1250);
PAINT GREEN (-2975 1250);
DISPLAY INVISIBLE (-2975 1250);
FORCEPROP 2 LAST PATH I179
J 2
(-3275 1425);
DISPLAY 1.021277 (-3275 1425);
DISPLAY INVISIBLE (-3275 1425);
FORCEADD OFFPAGE..1
(-4250 2975);
FORCEPROP 2 LAST $XR0 54 
J 0
(-4471 2975);
DISPLAY 0.638298 (-4471 2975);
PAINT MONO (-4471 2975);
FORCEPROP 2 LAST CDS_LIB standard
J 0
(-4250 2975);
PAINT MONO (-4250 2975);
DISPLAY INVISIBLE (-4250 2975);
FORCEPROP 1 LAST OFFPAGE TRUE
J 0
(-3925 2850);
DISPLAY 0.872340 (-3925 2850);
DISPLAY INVISIBLE (-3925 2850);
FORCEPROP 1 LAST COMMENT_BODY TRUE
J 0
(-4125 2875);
DISPLAY 0.872340 (-4125 2875);
PAINT GREEN (-4125 2875);
DISPLAY INVISIBLE (-4125 2875);
FORCEPROP 2 LAST PATH I18
J 0
(-4200 3050);
DISPLAY 1.021277 (-4200 3050);
DISPLAY INVISIBLE (-4200 3050);
FORCEADD Q_RES..1
(-4300 1425);
FORCEPROP 1 LAST PART_NUMBER CS04992FB07
J 0
(-4200 1400);
DISPLAY 0.404255 (-4200 1400);
DISPLAY INVISIBLE (-4200 1400);
FORCEPROP 1 LAST VALUE 49.9
J 2
(-4075 1425);
DISPLAY 0.510638 (-4075 1425);
FORCEPROP 1 LAST MATERIAL CHIP
J 0
(-4450 1400);
DISPLAY 0.404255 (-4450 1400);
FORCEPROP 1 LAST $LOCATION R3897
J 0
(-4550 1425);
DISPLAY 0.638298 (-4550 1425);
FORCEPROP 1 LASTPIN (-4400 1425) $PN 1
J 0
(-4388 1437);
DISPLAY 0.787234 (-4388 1437);
PAINT MONO (-4388 1437);
FORCEPROP 1 LASTPIN (-4200 1425) $PN 2
J 0
(-4238 1437);
DISPLAY 0.787234 (-4238 1437);
PAINT MONO (-4238 1437);
FORCEPROP 2 LAST CDS_LIB pure_quanta
J 0
(-4300 1425);
DISPLAY INVISIBLE (-4300 1425);
FORCEPROP 1 LAST PACK_TYPE 0402LF
J 0
(-4000 1425);
DISPLAY 0.510638 (-4000 1425);
DISPLAY INVISIBLE (-4000 1425);
FORCEPROP 1 LAST TOLERANCE 1%
J 0
(-4075 1425);
DISPLAY 0.510638 (-4075 1425);
DISPLAY INVISIBLE (-4075 1425);
FORCEPROP 1 LAST WATTAGE 1/16W
J 2
(-4000 1375);
DISPLAY 0.404255 (-4000 1375);
DISPLAY INVISIBLE (-4000 1375);
FORCEPROP 1 LAST PATH I180
J 0
(-4350 1575);
DISPLAY 0.978723 (-4350 1575);
PAINT WHITE (-4350 1575);
DISPLAY INVISIBLE (-4350 1575);
FORCEPROP 0 LAST CDS_LOCATION R3897
J 0
(-4450 1475);
DISPLAY 1.021277 (-4450 1475);
DISPLAY INVISIBLE (-4450 1475);
FORCEPROP 0 LAST $SEC 1
J 0
(-4450 1475);
DISPLAY 0.680851 (-4450 1475);
PAINT MONO (-4450 1475);
DISPLAY INVISIBLE (-4450 1475);
FORCEPROP 0 LAST CDS_SEC 1
J 0
(-4450 1475);
DISPLAY 1.021277 (-4450 1475);
DISPLAY INVISIBLE (-4450 1475);
FORCEADD OFFPAGE..1
(-4250 3175);
FORCEPROP 2 LAST $XR0 54 
J 0
(-4471 3175);
DISPLAY 0.638298 (-4471 3175);
PAINT MONO (-4471 3175);
FORCEPROP 2 LAST CDS_LIB standard
J 0
(-4250 3175);
PAINT MONO (-4250 3175);
DISPLAY INVISIBLE (-4250 3175);
FORCEPROP 1 LAST OFFPAGE TRUE
J 0
(-3925 3050);
DISPLAY 0.872340 (-3925 3050);
DISPLAY INVISIBLE (-3925 3050);
FORCEPROP 1 LAST COMMENT_BODY TRUE
J 0
(-4125 3075);
DISPLAY 0.872340 (-4125 3075);
PAINT GREEN (-4125 3075);
DISPLAY INVISIBLE (-4125 3075);
FORCEPROP 2 LAST PATH I19
J 0
(-4200 3250);
DISPLAY 1.021277 (-4200 3250);
DISPLAY INVISIBLE (-4200 3250);
FORCEADD Q_RES..2
(-3100 -25);
FORCEPROP 1 LAST PART_NUMBER CS41272FB07
J 0
(-3060 -150);
DISPLAY 0.978723 (-3060 -150);
DISPLAY INVISIBLE (-3060 -150);
FORCEPROP 1 LAST VALUE 127K
J 0
(-3055 50);
DISPLAY 0.978723 (-3055 50);
FORCEPROP 1 LAST TOLERANCE 1%
J 0
(-3055 0);
DISPLAY 0.978723 (-3055 0);
FORCEPROP 1 LAST WATTAGE 1/16W
J 0
(-3060 -50);
DISPLAY 0.978723 (-3060 -50);
FORCEPROP 1 LAST PACK_TYPE 0402LF
J 0
(-3060 -200);
DISPLAY 0.978723 (-3060 -200);
FORCEPROP 1 LAST MATERIAL CHIP
J 0
(-3060 -100);
DISPLAY 0.978723 (-3060 -100);
FORCEPROP 1 LAST $LOCATION R48
J 0
(-3055 100);
DISPLAY 0.978723 (-3055 100);
FORCEPROP 1 LASTPIN (-3100 75) $PN 1
J 0
(-3095 37);
DISPLAY 0.787234 (-3095 37);
FORCEPROP 1 LASTPIN (-3100 -125) $PN 2
J 0
(-3095 -115);
DISPLAY 0.787234 (-3095 -115);
FORCEPROP 2 LAST CDS_LIB pure_quanta
J 0
(-3100 -25);
PAINT MONO (-3100 -25);
DISPLAY INVISIBLE (-3100 -25);
FORCEPROP 1 LAST PATH I2
J 0
(-3050 150);
DISPLAY 0.978723 (-3050 150);
PAINT WHITE (-3050 150);
DISPLAY INVISIBLE (-3050 150);
FORCEPROP 1 LAST $LOCATION R48
J 0
(-3050 200);
DISPLAY 1.021277 (-3050 200);
DISPLAY INVISIBLE (-3050 200);
FORCEPROP 2 LAST CDS_LOCATION R48
J 0
(-3050 200);
DISPLAY 1.021277 (-3050 200);
DISPLAY INVISIBLE (-3050 200);
FORCEPROP 2 LAST $SEC 1
J 0
(-3050 200);
DISPLAY 0.680851 (-3050 200);
PAINT MONO (-3050 200);
DISPLAY INVISIBLE (-3050 200);
FORCEPROP 2 LAST CDS_SEC 1
J 0
(-3050 200);
DISPLAY 1.021277 (-3050 200);
DISPLAY INVISIBLE (-3050 200);
FORCEADD OFFPAGE..1
(-4250 3125);
FORCEPROP 2 LAST $XR0 54 
J 0
(-4471 3125);
DISPLAY 0.638298 (-4471 3125);
PAINT MONO (-4471 3125);
FORCEPROP 2 LAST CDS_LIB standard
J 0
(-4250 3125);
PAINT MONO (-4250 3125);
DISPLAY INVISIBLE (-4250 3125);
FORCEPROP 1 LAST OFFPAGE TRUE
J 0
(-3925 3000);
DISPLAY 0.872340 (-3925 3000);
DISPLAY INVISIBLE (-3925 3000);
FORCEPROP 1 LAST COMMENT_BODY TRUE
J 0
(-4125 3025);
DISPLAY 0.872340 (-4125 3025);
PAINT GREEN (-4125 3025);
DISPLAY INVISIBLE (-4125 3025);
FORCEPROP 2 LAST PATH I20
J 0
(-4200 3200);
DISPLAY 1.021277 (-4200 3200);
DISPLAY INVISIBLE (-4200 3200);
FORCEADD OFFPAGE..1
(-4250 3275);
FORCEPROP 2 LAST $XR1 105 
J 0
(-4591 3275);
DISPLAY 0.638298 (-4591 3275);
PAINT MONO (-4591 3275);
FORCEPROP 2 LAST $XR0 54 
J 0
(-4471 3275);
DISPLAY 0.638298 (-4471 3275);
PAINT MONO (-4471 3275);
FORCEPROP 2 LAST CDS_LIB standard
J 0
(-4250 3275);
PAINT MONO (-4250 3275);
DISPLAY INVISIBLE (-4250 3275);
FORCEPROP 1 LAST OFFPAGE TRUE
J 0
(-3925 3150);
DISPLAY 0.872340 (-3925 3150);
DISPLAY INVISIBLE (-3925 3150);
FORCEPROP 1 LAST COMMENT_BODY TRUE
J 0
(-4125 3175);
DISPLAY 0.872340 (-4125 3175);
PAINT GREEN (-4125 3175);
DISPLAY INVISIBLE (-4125 3175);
FORCEPROP 2 LAST PATH I21
J 0
(-4200 3350);
DISPLAY 1.021277 (-4200 3350);
DISPLAY INVISIBLE (-4200 3350);
FORCEADD OFFPAGE..1
(-4250 3325);
FORCEPROP 2 LAST $XR1 105 
J 0
(-4591 3325);
DISPLAY 0.638298 (-4591 3325);
PAINT MONO (-4591 3325);
FORCEPROP 2 LAST $XR0 54 
J 0
(-4471 3325);
DISPLAY 0.638298 (-4471 3325);
PAINT MONO (-4471 3325);
FORCEPROP 2 LAST CDS_LIB standard
J 0
(-4250 3325);
PAINT MONO (-4250 3325);
DISPLAY INVISIBLE (-4250 3325);
FORCEPROP 1 LAST OFFPAGE TRUE
J 0
(-3925 3200);
DISPLAY 0.872340 (-3925 3200);
DISPLAY INVISIBLE (-3925 3200);
FORCEPROP 1 LAST COMMENT_BODY TRUE
J 0
(-4125 3225);
DISPLAY 0.872340 (-4125 3225);
PAINT GREEN (-4125 3225);
DISPLAY INVISIBLE (-4125 3225);
FORCEPROP 2 LAST PATH I22
J 0
(-4200 3400);
DISPLAY 1.021277 (-4200 3400);
DISPLAY INVISIBLE (-4200 3400);
FORCEADD OFFPAGE..1
(-4250 3750);
FORCEPROP 2 LAST $XR1 105 
J 0
(-4591 3750);
DISPLAY 0.638298 (-4591 3750);
PAINT MONO (-4591 3750);
FORCEPROP 2 LAST $XR0 54 
J 0
(-4471 3750);
DISPLAY 0.638298 (-4471 3750);
PAINT MONO (-4471 3750);
FORCEPROP 2 LAST CDS_LIB standard
J 0
(-4250 3750);
PAINT MONO (-4250 3750);
DISPLAY INVISIBLE (-4250 3750);
FORCEPROP 1 LAST OFFPAGE TRUE
J 0
(-3925 3625);
DISPLAY 0.872340 (-3925 3625);
DISPLAY INVISIBLE (-3925 3625);
FORCEPROP 1 LAST COMMENT_BODY TRUE
J 0
(-4125 3650);
DISPLAY 0.872340 (-4125 3650);
PAINT GREEN (-4125 3650);
DISPLAY INVISIBLE (-4125 3650);
FORCEPROP 2 LAST PATH I23
J 0
(-4200 3825);
DISPLAY 1.021277 (-4200 3825);
DISPLAY INVISIBLE (-4200 3825);
FORCEADD OFFPAGE..1
(-4250 4150);
FORCEPROP 2 LAST $XR1 105 
J 0
(-4591 4150);
DISPLAY 0.638298 (-4591 4150);
PAINT MONO (-4591 4150);
FORCEPROP 2 LAST $XR0 54 
J 0
(-4471 4150);
DISPLAY 0.638298 (-4471 4150);
PAINT MONO (-4471 4150);
FORCEPROP 2 LAST CDS_LIB standard
J 0
(-4250 4150);
PAINT MONO (-4250 4150);
DISPLAY INVISIBLE (-4250 4150);
FORCEPROP 1 LAST OFFPAGE TRUE
J 0
(-3925 4025);
DISPLAY 0.872340 (-3925 4025);
DISPLAY INVISIBLE (-3925 4025);
FORCEPROP 1 LAST COMMENT_BODY TRUE
J 0
(-4125 4050);
DISPLAY 0.872340 (-4125 4050);
PAINT GREEN (-4125 4050);
DISPLAY INVISIBLE (-4125 4050);
FORCEPROP 2 LAST PATH I24
J 0
(-4200 4225);
DISPLAY 1.021277 (-4200 4225);
DISPLAY INVISIBLE (-4200 4225);
FORCEADD SCONN288_ADR50017P130CC..1
(-2500 2400);
FORCEPROP 1 LAST PART_NUMBER DFHST8FS461
J 0
(-2945 4422);
DISPLAY 0.723404 (-2945 4422);
PAINT GREEN (-2945 4422);
DISPLAY INVISIBLE (-2945 4422);
FORCEPROP 1 LAST MATERIAL IO
J 0
(-2945 4295);
DISPLAY 0.723404 (-2945 4295);
PAINT GREEN (-2945 4295);
FORCEPROP 2 LAST VALUE SCONN288_ADR50017-P130CC
J 0
(-2950 4525);
DISPLAY 1.021277 (-2950 4525);
FORCEPROP 2 LAST PART_TYPE SMLF
J 0
(-2950 4575);
DISPLAY 1.021277 (-2950 4575);
FORCEPROP 1 LAST $LOCATION J23
J 0
(-2950 4475);
DISPLAY 0.723404 (-2950 4475);
PAINT GREEN (-2950 4475);
FORCEPROP 0 LASTPIN (-3100 1775) $PN 62
J 2
(-3110 1785);
DISPLAY 0.680851 (-3110 1785);
PAINT MONO (-3110 1785);
FORCEPROP 0 LASTPIN (-3100 3825) $PN 66
J 2
(-3110 3835);
DISPLAY 0.680851 (-3110 3835);
PAINT MONO (-3110 3835);
FORCEPROP 0 LASTPIN (-3100 3425) $PN 76
J 2
(-3110 3435);
DISPLAY 0.680851 (-3110 3435);
PAINT MONO (-3110 3435);
FORCEPROP 0 LASTPIN (-3100 3875) $PN 211
J 2
(-3110 3885);
DISPLAY 0.680851 (-3110 3885);
PAINT MONO (-3110 3885);
FORCEPROP 0 LASTPIN (-3100 3475) $PN 221
J 2
(-3110 3485);
DISPLAY 0.680851 (-3110 3485);
PAINT MONO (-3110 3485);
FORCEPROP 0 LASTPIN (-3100 3925) $PN 68
J 2
(-3110 3935);
DISPLAY 0.680851 (-3110 3935);
PAINT MONO (-3110 3935);
FORCEPROP 0 LASTPIN (-3100 3525) $PN 78
J 2
(-3110 3535);
DISPLAY 0.680851 (-3110 3535);
PAINT MONO (-3110 3535);
FORCEPROP 0 LASTPIN (-3100 3975) $PN 213
J 2
(-3110 3985);
DISPLAY 0.680851 (-3110 3985);
PAINT MONO (-3110 3985);
FORCEPROP 0 LASTPIN (-3100 3575) $PN 223
J 2
(-3110 3585);
DISPLAY 0.680851 (-3110 3585);
PAINT MONO (-3110 3585);
FORCEPROP 0 LASTPIN (-3100 4025) $PN 70
J 2
(-3110 4035);
DISPLAY 0.680851 (-3110 4035);
PAINT MONO (-3110 4035);
FORCEPROP 0 LASTPIN (-3100 3625) $PN 80
J 2
(-3110 3635);
DISPLAY 0.680851 (-3110 3635);
PAINT MONO (-3110 3635);
FORCEPROP 0 LASTPIN (-3100 4075) $PN 215
J 2
(-3110 4085);
DISPLAY 0.680851 (-3110 4085);
PAINT MONO (-3110 4085);
FORCEPROP 0 LASTPIN (-3100 3675) $PN 225
J 2
(-3110 3685);
DISPLAY 0.680851 (-3110 3685);
PAINT MONO (-3110 3685);
FORCEPROP 0 LASTPIN (-3100 4125) $PN 72
J 2
(-3110 4135);
DISPLAY 0.680851 (-3110 4135);
PAINT MONO (-3110 4135);
FORCEPROP 0 LASTPIN (-3100 3725) $PN 82
J 2
(-3110 3735);
DISPLAY 0.680851 (-3110 3735);
PAINT MONO (-3110 3735);
FORCEPROP 0 LASTPIN (-3100 2375) $PN 51
J 2
(-3110 2385);
DISPLAY 0.680851 (-3110 2385);
PAINT MONO (-3110 2385);
FORCEPROP 0 LASTPIN (-3100 1925) $PN 96
J 2
(-3110 1935);
DISPLAY 0.680851 (-3110 1935);
PAINT MONO (-3110 1935);
FORCEPROP 0 LASTPIN (-3100 2425) $PN 53
J 2
(-3110 2435);
DISPLAY 0.680851 (-3110 2435);
PAINT MONO (-3110 2435);
FORCEPROP 0 LASTPIN (-3100 1975) $PN 98
J 2
(-3110 1985);
DISPLAY 0.680851 (-3110 1985);
PAINT MONO (-3110 1985);
FORCEPROP 0 LASTPIN (-3100 2475) $PN 196
J 2
(-3110 2485);
DISPLAY 0.680851 (-3110 2485);
PAINT MONO (-3110 2485);
FORCEPROP 0 LASTPIN (-3100 2025) $PN 241
J 2
(-3110 2035);
DISPLAY 0.680851 (-3110 2035);
PAINT MONO (-3110 2035);
FORCEPROP 0 LASTPIN (-3100 2525) $PN 198
J 2
(-3110 2535);
DISPLAY 0.680851 (-3110 2535);
PAINT MONO (-3110 2535);
FORCEPROP 0 LASTPIN (-3100 2075) $PN 243
J 2
(-3110 2085);
DISPLAY 0.680851 (-3110 2085);
PAINT MONO (-3110 2085);
FORCEPROP 0 LASTPIN (-3100 2575) $PN 58
J 2
(-3110 2585);
DISPLAY 0.680851 (-3110 2585);
PAINT MONO (-3110 2585);
FORCEPROP 0 LASTPIN (-3100 2125) $PN 89
J 2
(-3110 2135);
DISPLAY 0.680851 (-3110 2135);
PAINT MONO (-3110 2135);
FORCEPROP 0 LASTPIN (-3100 2625) $PN 60
J 2
(-3110 2635);
DISPLAY 0.680851 (-3110 2635);
PAINT MONO (-3110 2635);
FORCEPROP 0 LASTPIN (-3100 2175) $PN 91
J 2
(-3110 2185);
DISPLAY 0.680851 (-3110 2185);
PAINT MONO (-3110 2185);
FORCEPROP 0 LASTPIN (-3100 2675) $PN 203
J 2
(-3110 2685);
DISPLAY 0.680851 (-3110 2685);
PAINT MONO (-3110 2685);
FORCEPROP 0 LASTPIN (-3100 2225) $PN 234
J 2
(-3110 2235);
DISPLAY 0.680851 (-3110 2235);
PAINT MONO (-3110 2235);
FORCEPROP 0 LASTPIN (-3100 2725) $PN 205
J 2
(-3110 2735);
DISPLAY 0.680851 (-3110 2735);
PAINT MONO (-3110 2735);
FORCEPROP 0 LASTPIN (-3100 2275) $PN 236
J 2
(-3110 2285);
DISPLAY 0.680851 (-3110 2285);
PAINT MONO (-3110 2285);
FORCEPROP 0 LASTPIN (-3100 2825) $PN 218
J 2
(-3110 2835);
DISPLAY 0.680851 (-3110 2835);
PAINT MONO (-3110 2835);
FORCEPROP 0 LASTPIN (-3100 2875) $PN 217
J 2
(-3110 2885);
DISPLAY 0.680851 (-3110 2885);
PAINT MONO (-3110 2885);
FORCEPROP 0 LASTPIN (-3100 3125) $PN 64
J 2
(-3110 3135);
DISPLAY 0.680851 (-3110 3135);
PAINT MONO (-3110 3135);
FORCEPROP 0 LASTPIN (-3100 2975) $PN 84
J 2
(-3110 2985);
DISPLAY 0.680851 (-3110 2985);
PAINT MONO (-3110 2985);
FORCEPROP 0 LASTPIN (-3100 3175) $PN 209
J 2
(-3110 3185);
DISPLAY 0.680851 (-3110 3185);
PAINT MONO (-3110 3185);
FORCEPROP 0 LASTPIN (-3100 3025) $PN 229
J 2
(-3110 3035);
DISPLAY 0.680851 (-3110 3035);
PAINT MONO (-3110 3035);
FORCEPROP 0 LASTPIN (-1900 2575) $PN 7
J 0
(-1890 2585);
DISPLAY 0.680851 (-1890 2585);
PAINT MONO (-1890 2585);
FORCEPROP 0 LASTPIN (-1900 925) $PN 100
J 0
(-1890 935);
DISPLAY 0.680851 (-1890 935);
PAINT MONO (-1890 935);
FORCEPROP 0 LASTPIN (-1900 2625) $PN 9
J 0
(-1890 2635);
DISPLAY 0.680851 (-1890 2635);
PAINT MONO (-1890 2635);
FORCEPROP 0 LASTPIN (-1900 975) $PN 102
J 0
(-1890 985);
DISPLAY 0.680851 (-1890 985);
PAINT MONO (-1890 985);
FORCEPROP 0 LASTPIN (-1900 2675) $PN 152
J 0
(-1890 2685);
DISPLAY 0.680851 (-1890 2685);
PAINT MONO (-1890 2685);
FORCEPROP 0 LASTPIN (-1900 1025) $PN 245
J 0
(-1890 1035);
DISPLAY 0.680851 (-1890 1035);
PAINT MONO (-1890 1035);
FORCEPROP 0 LASTPIN (-1900 2725) $PN 154
J 0
(-1890 2735);
DISPLAY 0.680851 (-1890 2735);
PAINT MONO (-1890 2735);
FORCEPROP 0 LASTPIN (-1900 1075) $PN 247
J 0
(-1890 1085);
DISPLAY 0.680851 (-1890 1085);
PAINT MONO (-1890 1085);
FORCEPROP 0 LASTPIN (-1900 2775) $PN 14
J 0
(-1890 2785);
DISPLAY 0.680851 (-1890 2785);
PAINT MONO (-1890 2785);
FORCEPROP 0 LASTPIN (-1900 1125) $PN 107
J 0
(-1890 1135);
DISPLAY 0.680851 (-1890 1135);
PAINT MONO (-1890 1135);
FORCEPROP 0 LASTPIN (-1900 2825) $PN 16
J 0
(-1890 2835);
DISPLAY 0.680851 (-1890 2835);
PAINT MONO (-1890 2835);
FORCEPROP 0 LASTPIN (-1900 1175) $PN 109
J 0
(-1890 1185);
DISPLAY 0.680851 (-1890 1185);
PAINT MONO (-1890 1185);
FORCEPROP 0 LASTPIN (-1900 2875) $PN 159
J 0
(-1890 2885);
DISPLAY 0.680851 (-1890 2885);
PAINT MONO (-1890 2885);
FORCEPROP 0 LASTPIN (-1900 1225) $PN 252
J 0
(-1890 1235);
DISPLAY 0.680851 (-1890 1235);
PAINT MONO (-1890 1235);
FORCEPROP 0 LASTPIN (-1900 2925) $PN 161
J 0
(-1890 2935);
DISPLAY 0.680851 (-1890 2935);
PAINT MONO (-1890 2935);
FORCEPROP 0 LASTPIN (-1900 1275) $PN 254
J 0
(-1890 1285);
DISPLAY 0.680851 (-1890 1285);
PAINT MONO (-1890 1285);
FORCEPROP 0 LASTPIN (-1900 2975) $PN 18
J 0
(-1890 2985);
DISPLAY 0.680851 (-1890 2985);
PAINT MONO (-1890 2985);
FORCEPROP 0 LASTPIN (-1900 1325) $PN 111
J 0
(-1890 1335);
DISPLAY 0.680851 (-1890 1335);
PAINT MONO (-1890 1335);
FORCEPROP 0 LASTPIN (-1900 3025) $PN 20
J 0
(-1890 3035);
DISPLAY 0.680851 (-1890 3035);
PAINT MONO (-1890 3035);
FORCEPROP 0 LASTPIN (-1900 1375) $PN 113
J 0
(-1890 1385);
DISPLAY 0.680851 (-1890 1385);
PAINT MONO (-1890 1385);
FORCEPROP 0 LASTPIN (-1900 3075) $PN 163
J 0
(-1890 3085);
DISPLAY 0.680851 (-1890 3085);
PAINT MONO (-1890 3085);
FORCEPROP 0 LASTPIN (-1900 1425) $PN 256
J 0
(-1890 1435);
DISPLAY 0.680851 (-1890 1435);
PAINT MONO (-1890 1435);
FORCEPROP 0 LASTPIN (-1900 3125) $PN 165
J 0
(-1890 3135);
DISPLAY 0.680851 (-1890 3135);
PAINT MONO (-1890 3135);
FORCEPROP 0 LASTPIN (-1900 1475) $PN 258
J 0
(-1890 1485);
DISPLAY 0.680851 (-1890 1485);
PAINT MONO (-1890 1485);
FORCEPROP 0 LASTPIN (-1900 3175) $PN 25
J 0
(-1890 3185);
DISPLAY 0.680851 (-1890 3185);
PAINT MONO (-1890 3185);
FORCEPROP 0 LASTPIN (-1900 1525) $PN 118
J 0
(-1890 1535);
DISPLAY 0.680851 (-1890 1535);
PAINT MONO (-1890 1535);
FORCEPROP 0 LASTPIN (-1900 3225) $PN 27
J 0
(-1890 3235);
DISPLAY 0.680851 (-1890 3235);
PAINT MONO (-1890 3235);
FORCEPROP 0 LASTPIN (-1900 1575) $PN 120
J 0
(-1890 1585);
DISPLAY 0.680851 (-1890 1585);
PAINT MONO (-1890 1585);
FORCEPROP 0 LASTPIN (-1900 3275) $PN 170
J 0
(-1890 3285);
DISPLAY 0.680851 (-1890 3285);
PAINT MONO (-1890 3285);
FORCEPROP 0 LASTPIN (-1900 1625) $PN 263
J 0
(-1890 1635);
DISPLAY 0.680851 (-1890 1635);
PAINT MONO (-1890 1635);
FORCEPROP 0 LASTPIN (-1900 3325) $PN 172
J 0
(-1890 3335);
DISPLAY 0.680851 (-1890 3335);
PAINT MONO (-1890 3335);
FORCEPROP 0 LASTPIN (-1900 1675) $PN 265
J 0
(-1890 1685);
DISPLAY 0.680851 (-1890 1685);
PAINT MONO (-1890 1685);
FORCEPROP 0 LASTPIN (-1900 3375) $PN 29
J 0
(-1890 3385);
DISPLAY 0.680851 (-1890 3385);
PAINT MONO (-1890 3385);
FORCEPROP 0 LASTPIN (-1900 1725) $PN 122
J 0
(-1890 1735);
DISPLAY 0.680851 (-1890 1735);
PAINT MONO (-1890 1735);
FORCEPROP 0 LASTPIN (-1900 3425) $PN 31
J 0
(-1890 3435);
DISPLAY 0.680851 (-1890 3435);
PAINT MONO (-1890 3435);
FORCEPROP 0 LASTPIN (-1900 1775) $PN 124
J 0
(-1890 1785);
DISPLAY 0.680851 (-1890 1785);
PAINT MONO (-1890 1785);
FORCEPROP 0 LASTPIN (-1900 3475) $PN 174
J 0
(-1890 3485);
DISPLAY 0.680851 (-1890 3485);
PAINT MONO (-1890 3485);
FORCEPROP 0 LASTPIN (-1900 1825) $PN 267
J 0
(-1890 1835);
DISPLAY 0.680851 (-1890 1835);
PAINT MONO (-1890 1835);
FORCEPROP 0 LASTPIN (-1900 3525) $PN 176
J 0
(-1890 3535);
DISPLAY 0.680851 (-1890 3535);
PAINT MONO (-1890 3535);
FORCEPROP 0 LASTPIN (-1900 1875) $PN 269
J 0
(-1890 1885);
DISPLAY 0.680851 (-1890 1885);
PAINT MONO (-1890 1885);
FORCEPROP 0 LASTPIN (-1900 3575) $PN 36
J 0
(-1890 3585);
DISPLAY 0.680851 (-1890 3585);
PAINT MONO (-1890 3585);
FORCEPROP 0 LASTPIN (-1900 1925) $PN 129
J 0
(-1890 1935);
DISPLAY 0.680851 (-1890 1935);
PAINT MONO (-1890 1935);
FORCEPROP 0 LASTPIN (-1900 3625) $PN 38
J 0
(-1890 3635);
DISPLAY 0.680851 (-1890 3635);
PAINT MONO (-1890 3635);
FORCEPROP 0 LASTPIN (-1900 1975) $PN 131
J 0
(-1890 1985);
DISPLAY 0.680851 (-1890 1985);
PAINT MONO (-1890 1985);
FORCEPROP 0 LASTPIN (-1900 3675) $PN 181
J 0
(-1890 3685);
DISPLAY 0.680851 (-1890 3685);
PAINT MONO (-1890 3685);
FORCEPROP 0 LASTPIN (-1900 2025) $PN 274
J 0
(-1890 2035);
DISPLAY 0.680851 (-1890 2035);
PAINT MONO (-1890 2035);
FORCEPROP 0 LASTPIN (-1900 3725) $PN 183
J 0
(-1890 3735);
DISPLAY 0.680851 (-1890 3735);
PAINT MONO (-1890 3735);
FORCEPROP 0 LASTPIN (-1900 2075) $PN 276
J 0
(-1890 2085);
DISPLAY 0.680851 (-1890 2085);
PAINT MONO (-1890 2085);
FORCEPROP 0 LASTPIN (-1900 3775) $PN 40
J 0
(-1890 3785);
DISPLAY 0.680851 (-1890 3785);
PAINT MONO (-1890 3785);
FORCEPROP 0 LASTPIN (-1900 2125) $PN 133
J 0
(-1890 2135);
DISPLAY 0.680851 (-1890 2135);
PAINT MONO (-1890 2135);
FORCEPROP 0 LASTPIN (-1900 3825) $PN 42
J 0
(-1890 3835);
DISPLAY 0.680851 (-1890 3835);
PAINT MONO (-1890 3835);
FORCEPROP 0 LASTPIN (-1900 2175) $PN 135
J 0
(-1890 2185);
DISPLAY 0.680851 (-1890 2185);
PAINT MONO (-1890 2185);
FORCEPROP 0 LASTPIN (-1900 3875) $PN 185
J 0
(-1890 3885);
DISPLAY 0.680851 (-1890 3885);
PAINT MONO (-1890 3885);
FORCEPROP 0 LASTPIN (-1900 2225) $PN 278
J 0
(-1890 2235);
DISPLAY 0.680851 (-1890 2235);
PAINT MONO (-1890 2235);
FORCEPROP 0 LASTPIN (-1900 3925) $PN 187
J 0
(-1890 3935);
DISPLAY 0.680851 (-1890 3935);
PAINT MONO (-1890 3935);
FORCEPROP 0 LASTPIN (-1900 2275) $PN 280
J 0
(-1890 2285);
DISPLAY 0.680851 (-1890 2285);
PAINT MONO (-1890 2285);
FORCEPROP 0 LASTPIN (-1900 3975) $PN 47
J 0
(-1890 3985);
DISPLAY 0.680851 (-1890 3985);
PAINT MONO (-1890 3985);
FORCEPROP 0 LASTPIN (-1900 2325) $PN 140
J 0
(-1890 2335);
DISPLAY 0.680851 (-1890 2335);
PAINT MONO (-1890 2335);
FORCEPROP 0 LASTPIN (-1900 4025) $PN 49
J 0
(-1890 4035);
DISPLAY 0.680851 (-1890 4035);
PAINT MONO (-1890 4035);
FORCEPROP 0 LASTPIN (-1900 2375) $PN 142
J 0
(-1890 2385);
DISPLAY 0.680851 (-1890 2385);
PAINT MONO (-1890 2385);
FORCEPROP 0 LASTPIN (-1900 4075) $PN 192
J 0
(-1890 4085);
DISPLAY 0.680851 (-1890 4085);
PAINT MONO (-1890 4085);
FORCEPROP 0 LASTPIN (-1900 2425) $PN 285
J 0
(-1890 2435);
DISPLAY 0.680851 (-1890 2435);
PAINT MONO (-1890 2435);
FORCEPROP 0 LASTPIN (-1900 4125) $PN 194
J 0
(-1890 4135);
DISPLAY 0.680851 (-1890 4135);
PAINT MONO (-1890 4135);
FORCEPROP 0 LASTPIN (-1900 2475) $PN 287
J 0
(-1890 2485);
DISPLAY 0.680851 (-1890 2485);
PAINT MONO (-1890 2485);
FORCEPROP 0 LASTPIN (-3100 1625) $PN 148
J 2
(-3110 1635);
DISPLAY 0.680851 (-3110 1635);
PAINT MONO (-3110 1635);
FORCEPROP 0 LASTPIN (-3100 1525) $PN 4
J 2
(-3110 1535);
DISPLAY 0.680851 (-3110 1535);
PAINT MONO (-3110 1535);
FORCEPROP 0 LASTPIN (-3100 1575) $PN 5
J 2
(-3110 1585);
DISPLAY 0.680851 (-3110 1585);
PAINT MONO (-3110 1585);
FORCEPROP 0 LASTPIN (-3100 725) $PN 86
J 2
(-3110 735);
DISPLAY 0.680851 (-3110 735);
PAINT MONO (-3110 735);
FORCEPROP 0 LASTPIN (-3100 675) $PN 87
J 2
(-3110 685);
DISPLAY 0.680851 (-3110 685);
PAINT MONO (-3110 685);
FORCEPROP 0 LASTPIN (-3100 3325) $PN 74
J 2
(-3110 3335);
DISPLAY 0.680851 (-3110 3335);
PAINT MONO (-3110 3335);
FORCEPROP 0 LASTPIN (-3100 3275) $PN 227
J 2
(-3110 3285);
DISPLAY 0.680851 (-3110 3285);
PAINT MONO (-3110 3285);
FORCEPROP 0 LASTPIN (-3100 1275) $PN 147
J 2
(-3110 1285);
DISPLAY 0.680851 (-3110 1285);
PAINT MONO (-3110 1285);
FORCEPROP 0 LASTPIN (-3100 1825) $PN 207
J 2
(-3110 1835);
DISPLAY 0.680851 (-3110 1835);
PAINT MONO (-3110 1835);
FORCEPROP 0 LASTPIN (-3100 875) $PN 2
J 2
(-3110 885);
DISPLAY 0.680851 (-3110 885);
PAINT MONO (-3110 885);
FORCEPROP 0 LASTPIN (-3100 925) $PN 144
J 2
(-3110 935);
DISPLAY 0.680851 (-3110 935);
PAINT MONO (-3110 935);
FORCEPROP 0 LASTPIN (-3100 975) $PN 149
J 2
(-3110 985);
DISPLAY 0.680851 (-3110 985);
PAINT MONO (-3110 985);
FORCEPROP 0 LASTPIN (-3100 1025) $PN 150
J 2
(-3110 1035);
DISPLAY 0.680851 (-3110 1035);
PAINT MONO (-3110 1035);
FORCEPROP 0 LASTPIN (-3100 1075) $PN 220
J 2
(-3110 1085);
DISPLAY 0.680851 (-3110 1085);
PAINT MONO (-3110 1085);
FORCEPROP 0 LASTPIN (-3100 1125) $PN 231
J 2
(-3110 1135);
DISPLAY 0.680851 (-3110 1135);
PAINT MONO (-3110 1135);
FORCEPROP 0 LASTPIN (-3100 1175) $PN 232
J 2
(-3110 1185);
DISPLAY 0.680851 (-3110 1185);
PAINT MONO (-3110 1185);
FORCEPROP 0 LASTPIN (-3100 1675) $PN 3
J 2
(-3110 1685);
DISPLAY 0.680851 (-3110 1685);
PAINT MONO (-3110 1685);
FORCEPROP 1 LAST NEEDS_NO_SIZE TRUE
J 0
(-2500 2400);
DISPLAY 0.723404 (-2500 2400);
PAINT GREEN (-2500 2400);
DISPLAY INVISIBLE (-2500 2400);
FORCEPROP 1 LAST CDS_LMAN_SYM_OUTLINE -450,1875,450,-1875
J 0
(-2500 2400);
DISPLAY 0.468085 (-2500 2400);
PAINT GREEN (-2500 2400);
DISPLAY INVISIBLE (-2500 2400);
FORCEPROP 2 LAST CDS_LIB pure_quanta
J 0
(-2500 2400);
DISPLAY INVISIBLE (-2500 2400);
FORCEPROP 1 LAST PATH I25
J 0
(-2500 2400);
DISPLAY 0.723404 (-2500 2400);
PAINT GREEN (-2500 2400);
DISPLAY INVISIBLE (-2500 2400);
FORCEPROP 2 LAST CDS_LOCATION J23
J 0
(-2950 4625);
DISPLAY 1.021277 (-2950 4625);
DISPLAY INVISIBLE (-2950 4625);
FORCEPROP 0 LAST $SEC 1
J 0
(-2925 4625);
DISPLAY 0.680851 (-2925 4625);
PAINT MONO (-2925 4625);
DISPLAY INVISIBLE (-2925 4625);
FORCEPROP 2 LAST CDS_SEC 1
J 0
(-2950 4625);
DISPLAY 1.021277 (-2950 4625);
DISPLAY INVISIBLE (-2950 4625);
FORCEADD TAP..1
R 2
(-3325 2025);
FORCEPROP 3 LASTPIN (-3275 2025) SIG_NAME M_D_CPU1_SB_CB<2>
J 0
(-3265 2035);
DISPLAY 0.659574 (-3265 2035);
PAINT MONO (-3265 2035);
DISPLAY INVISIBLE (-3265 2035);
FORCEPROP 1 LASTPIN (-3275 2025) BN 2
J 2
(-3263 2033);
DISPLAY 0.680851 (-3263 2033);
PAINT GREEN (-3263 2033);
FORCEPROP 2 LAST CDS_LIB standard
J 0
(-3325 2025);
DISPLAY INVISIBLE (-3325 2025);
FORCEPROP 1 LAST BODY_TYPE PLUMBING
J 2
(-3325 2075);
DISPLAY 0.872340 (-3325 2075);
PAINT GREEN (-3325 2075);
DISPLAY INVISIBLE (-3325 2075);
FORCEPROP 1 LAST HDL_TAP TRUE
J 2
(-3650 1900);
DISPLAY 0.872340 (-3650 1900);
DISPLAY INVISIBLE (-3650 1900);
FORCEPROP 1 LAST PATH I26
J 2
(-3323 2025);
DISPLAY 0.872340 (-3323 2025);
PAINT GREEN (-3323 2025);
DISPLAY INVISIBLE (-3323 2025);
FORCEADD TAP..1
R 2
(-3325 2075);
FORCEPROP 3 LASTPIN (-3275 2075) SIG_NAME M_D_CPU1_SB_CB<3>
J 0
(-3265 2085);
DISPLAY 0.659574 (-3265 2085);
PAINT MONO (-3265 2085);
DISPLAY INVISIBLE (-3265 2085);
FORCEPROP 1 LASTPIN (-3275 2075) BN 3
J 2
(-3263 2083);
DISPLAY 0.680851 (-3263 2083);
PAINT GREEN (-3263 2083);
FORCEPROP 2 LAST CDS_LIB standard
J 0
(-3325 2075);
DISPLAY INVISIBLE (-3325 2075);
FORCEPROP 1 LAST BODY_TYPE PLUMBING
J 2
(-3325 2125);
DISPLAY 0.872340 (-3325 2125);
PAINT GREEN (-3325 2125);
DISPLAY INVISIBLE (-3325 2125);
FORCEPROP 1 LAST HDL_TAP TRUE
J 2
(-3650 1950);
DISPLAY 0.872340 (-3650 1950);
DISPLAY INVISIBLE (-3650 1950);
FORCEPROP 1 LAST PATH I27
J 2
(-3323 2075);
DISPLAY 0.872340 (-3323 2075);
PAINT GREEN (-3323 2075);
DISPLAY INVISIBLE (-3323 2075);
FORCEADD TAP..1
R 2
(-3325 1975);
FORCEPROP 3 LASTPIN (-3275 1975) SIG_NAME M_D_CPU1_SB_CB<1>
J 0
(-3265 1985);
DISPLAY 0.659574 (-3265 1985);
PAINT MONO (-3265 1985);
DISPLAY INVISIBLE (-3265 1985);
FORCEPROP 1 LASTPIN (-3275 1975) BN 1
J 2
(-3263 1983);
DISPLAY 0.680851 (-3263 1983);
PAINT GREEN (-3263 1983);
FORCEPROP 2 LAST CDS_LIB standard
J 0
(-3325 1975);
DISPLAY INVISIBLE (-3325 1975);
FORCEPROP 1 LAST BODY_TYPE PLUMBING
J 2
(-3325 2025);
DISPLAY 0.872340 (-3325 2025);
PAINT GREEN (-3325 2025);
DISPLAY INVISIBLE (-3325 2025);
FORCEPROP 1 LAST HDL_TAP TRUE
J 2
(-3650 1850);
DISPLAY 0.872340 (-3650 1850);
DISPLAY INVISIBLE (-3650 1850);
FORCEPROP 1 LAST PATH I28
J 2
(-3323 1975);
DISPLAY 0.872340 (-3323 1975);
PAINT GREEN (-3323 1975);
DISPLAY INVISIBLE (-3323 1975);
FORCEADD TAP..1
R 2
(-3325 1925);
FORCEPROP 3 LASTPIN (-3275 1925) SIG_NAME M_D_CPU1_SB_CB<0>
J 0
(-3265 1935);
DISPLAY 0.659574 (-3265 1935);
PAINT MONO (-3265 1935);
DISPLAY INVISIBLE (-3265 1935);
FORCEPROP 1 LASTPIN (-3275 1925) BN 0
J 2
(-3263 1933);
DISPLAY 0.680851 (-3263 1933);
PAINT GREEN (-3263 1933);
FORCEPROP 2 LAST CDS_LIB standard
J 0
(-3325 1925);
PAINT MONO (-3325 1925);
DISPLAY INVISIBLE (-3325 1925);
FORCEPROP 1 LAST BODY_TYPE PLUMBING
J 2
(-3325 1975);
DISPLAY 0.872340 (-3325 1975);
PAINT GREEN (-3325 1975);
DISPLAY INVISIBLE (-3325 1975);
FORCEPROP 1 LAST HDL_TAP TRUE
J 2
(-3650 1800);
DISPLAY 0.872340 (-3650 1800);
DISPLAY INVISIBLE (-3650 1800);
FORCEPROP 1 LAST PATH I29
J 2
(-3323 1925);
DISPLAY 0.872340 (-3323 1925);
PAINT GREEN (-3323 1925);
DISPLAY INVISIBLE (-3323 1925);
FORCEADD OFFPAGE..2
R 2
(-4250 175);
FORCEPROP 2 LAST $XR0 104 
J 0
(-4505 175);
DISPLAY 0.638298 (-4505 175);
PAINT MONO (-4505 175);
FORCEPROP 2 LAST CDS_LIB standard
J 0
(-4250 175);
PAINT MONO (-4250 175);
DISPLAY INVISIBLE (-4250 175);
FORCEPROP 1 LAST OFFPAGE TRUE
J 2
(-4575 50);
DISPLAY 0.872340 (-4575 50);
DISPLAY INVISIBLE (-4575 50);
FORCEPROP 1 LAST COMMENT_BODY TRUE
J 2
(-4205 80);
DISPLAY 0.872340 (-4205 80);
PAINT GREEN (-4205 80);
DISPLAY INVISIBLE (-4205 80);
FORCEPROP 2 LAST PATH I3
J 0
(-4200 250);
DISPLAY 1.021277 (-4200 250);
DISPLAY INVISIBLE (-4200 250);
FORCEADD TAP..1
(-1675 1025);
FORCEPROP 3 LASTPIN (-1725 1025) SIG_NAME M_D_CPU1_SB_DQ<2>
J 0
(-1715 1035);
DISPLAY 0.659574 (-1715 1035);
PAINT MONO (-1715 1035);
DISPLAY INVISIBLE (-1715 1035);
FORCEPROP 1 LASTPIN (-1725 1025) BN 2
J 0
(-1737 1033);
DISPLAY 0.680851 (-1737 1033);
PAINT GREEN (-1737 1033);
FORCEPROP 2 LAST CDS_LIB standard
J 0
(-1675 1025);
PAINT MONO (-1675 1025);
DISPLAY INVISIBLE (-1675 1025);
FORCEPROP 1 LAST BODY_TYPE PLUMBING
J 0
(-1675 1075);
DISPLAY 0.872340 (-1675 1075);
PAINT GREEN (-1675 1075);
DISPLAY INVISIBLE (-1675 1075);
FORCEPROP 1 LAST HDL_TAP TRUE
J 0
(-1350 900);
DISPLAY 0.872340 (-1350 900);
DISPLAY INVISIBLE (-1350 900);
FORCEPROP 1 LAST PATH I30
J 0
(-1677 1025);
DISPLAY 0.872340 (-1677 1025);
PAINT GREEN (-1677 1025);
DISPLAY INVISIBLE (-1677 1025);
FORCEADD TAP..1
(-1675 1075);
FORCEPROP 3 LASTPIN (-1725 1075) SIG_NAME M_D_CPU1_SB_DQ<3>
J 0
(-1715 1085);
DISPLAY 0.659574 (-1715 1085);
PAINT MONO (-1715 1085);
DISPLAY INVISIBLE (-1715 1085);
FORCEPROP 1 LASTPIN (-1725 1075) BN 3
J 0
(-1737 1083);
DISPLAY 0.680851 (-1737 1083);
PAINT GREEN (-1737 1083);
FORCEPROP 2 LAST CDS_LIB standard
J 0
(-1675 1075);
PAINT MONO (-1675 1075);
DISPLAY INVISIBLE (-1675 1075);
FORCEPROP 1 LAST BODY_TYPE PLUMBING
J 0
(-1675 1125);
DISPLAY 0.872340 (-1675 1125);
PAINT GREEN (-1675 1125);
DISPLAY INVISIBLE (-1675 1125);
FORCEPROP 1 LAST HDL_TAP TRUE
J 0
(-1350 950);
DISPLAY 0.872340 (-1350 950);
DISPLAY INVISIBLE (-1350 950);
FORCEPROP 1 LAST PATH I31
J 0
(-1677 1075);
DISPLAY 0.872340 (-1677 1075);
PAINT GREEN (-1677 1075);
DISPLAY INVISIBLE (-1677 1075);
FORCEADD TAP..1
(-1675 925);
FORCEPROP 3 LASTPIN (-1725 925) SIG_NAME M_D_CPU1_SB_DQ<0>
J 0
(-1715 935);
DISPLAY 0.659574 (-1715 935);
PAINT MONO (-1715 935);
DISPLAY INVISIBLE (-1715 935);
FORCEPROP 1 LASTPIN (-1725 925) BN 0
J 0
(-1737 933);
DISPLAY 0.680851 (-1737 933);
PAINT GREEN (-1737 933);
FORCEPROP 2 LAST CDS_LIB standard
J 0
(-1675 925);
PAINT MONO (-1675 925);
DISPLAY INVISIBLE (-1675 925);
FORCEPROP 1 LAST BODY_TYPE PLUMBING
J 0
(-1675 975);
DISPLAY 0.872340 (-1675 975);
PAINT GREEN (-1675 975);
DISPLAY INVISIBLE (-1675 975);
FORCEPROP 1 LAST HDL_TAP TRUE
J 0
(-1350 800);
DISPLAY 0.872340 (-1350 800);
DISPLAY INVISIBLE (-1350 800);
FORCEPROP 1 LAST PATH I32
J 0
(-1677 925);
DISPLAY 0.872340 (-1677 925);
PAINT GREEN (-1677 925);
DISPLAY INVISIBLE (-1677 925);
FORCEADD TAP..1
(-1675 975);
FORCEPROP 3 LASTPIN (-1725 975) SIG_NAME M_D_CPU1_SB_DQ<1>
J 0
(-1715 985);
DISPLAY 0.659574 (-1715 985);
PAINT MONO (-1715 985);
DISPLAY INVISIBLE (-1715 985);
FORCEPROP 1 LASTPIN (-1725 975) BN 1
J 0
(-1737 983);
DISPLAY 0.680851 (-1737 983);
PAINT GREEN (-1737 983);
FORCEPROP 2 LAST CDS_LIB standard
J 0
(-1675 975);
PAINT MONO (-1675 975);
DISPLAY INVISIBLE (-1675 975);
FORCEPROP 1 LAST BODY_TYPE PLUMBING
J 0
(-1675 1025);
DISPLAY 0.872340 (-1675 1025);
PAINT GREEN (-1675 1025);
DISPLAY INVISIBLE (-1675 1025);
FORCEPROP 1 LAST HDL_TAP TRUE
J 0
(-1350 850);
DISPLAY 0.872340 (-1350 850);
DISPLAY INVISIBLE (-1350 850);
FORCEPROP 1 LAST PATH I33
J 0
(-1677 975);
DISPLAY 0.872340 (-1677 975);
PAINT GREEN (-1677 975);
DISPLAY INVISIBLE (-1677 975);
FORCEADD TAP..1
(-1675 1225);
FORCEPROP 3 LASTPIN (-1725 1225) SIG_NAME M_D_CPU1_SB_DQ<6>
J 0
(-1715 1235);
DISPLAY 0.659574 (-1715 1235);
PAINT MONO (-1715 1235);
DISPLAY INVISIBLE (-1715 1235);
FORCEPROP 1 LASTPIN (-1725 1225) BN 6
J 0
(-1737 1233);
DISPLAY 0.680851 (-1737 1233);
PAINT GREEN (-1737 1233);
FORCEPROP 2 LAST CDS_LIB standard
J 0
(-1675 1225);
PAINT MONO (-1675 1225);
DISPLAY INVISIBLE (-1675 1225);
FORCEPROP 1 LAST BODY_TYPE PLUMBING
J 0
(-1675 1275);
DISPLAY 0.872340 (-1675 1275);
PAINT GREEN (-1675 1275);
DISPLAY INVISIBLE (-1675 1275);
FORCEPROP 1 LAST HDL_TAP TRUE
J 0
(-1350 1100);
DISPLAY 0.872340 (-1350 1100);
DISPLAY INVISIBLE (-1350 1100);
FORCEPROP 1 LAST PATH I34
J 0
(-1677 1225);
DISPLAY 0.872340 (-1677 1225);
PAINT GREEN (-1677 1225);
DISPLAY INVISIBLE (-1677 1225);
FORCEADD TAP..1
(-1675 1175);
FORCEPROP 3 LASTPIN (-1725 1175) SIG_NAME M_D_CPU1_SB_DQ<5>
J 0
(-1715 1185);
DISPLAY 0.659574 (-1715 1185);
PAINT MONO (-1715 1185);
DISPLAY INVISIBLE (-1715 1185);
FORCEPROP 1 LASTPIN (-1725 1175) BN 5
J 0
(-1737 1183);
DISPLAY 0.680851 (-1737 1183);
PAINT GREEN (-1737 1183);
FORCEPROP 2 LAST CDS_LIB standard
J 0
(-1675 1175);
PAINT MONO (-1675 1175);
DISPLAY INVISIBLE (-1675 1175);
FORCEPROP 1 LAST BODY_TYPE PLUMBING
J 0
(-1675 1225);
DISPLAY 0.872340 (-1675 1225);
PAINT GREEN (-1675 1225);
DISPLAY INVISIBLE (-1675 1225);
FORCEPROP 1 LAST HDL_TAP TRUE
J 0
(-1350 1050);
DISPLAY 0.872340 (-1350 1050);
DISPLAY INVISIBLE (-1350 1050);
FORCEPROP 1 LAST PATH I35
J 0
(-1677 1175);
DISPLAY 0.872340 (-1677 1175);
PAINT GREEN (-1677 1175);
DISPLAY INVISIBLE (-1677 1175);
FORCEADD TAP..1
(-1675 1125);
FORCEPROP 3 LASTPIN (-1725 1125) SIG_NAME M_D_CPU1_SB_DQ<4>
J 0
(-1715 1135);
DISPLAY 0.659574 (-1715 1135);
PAINT MONO (-1715 1135);
DISPLAY INVISIBLE (-1715 1135);
FORCEPROP 1 LASTPIN (-1725 1125) BN 4
J 0
(-1737 1133);
DISPLAY 0.680851 (-1737 1133);
PAINT GREEN (-1737 1133);
FORCEPROP 2 LAST CDS_LIB standard
J 0
(-1675 1125);
PAINT MONO (-1675 1125);
DISPLAY INVISIBLE (-1675 1125);
FORCEPROP 1 LAST BODY_TYPE PLUMBING
J 0
(-1675 1175);
DISPLAY 0.872340 (-1675 1175);
PAINT GREEN (-1675 1175);
DISPLAY INVISIBLE (-1675 1175);
FORCEPROP 1 LAST HDL_TAP TRUE
J 0
(-1350 1000);
DISPLAY 0.872340 (-1350 1000);
DISPLAY INVISIBLE (-1350 1000);
FORCEPROP 1 LAST PATH I36
J 0
(-1677 1125);
DISPLAY 0.872340 (-1677 1125);
PAINT GREEN (-1677 1125);
DISPLAY INVISIBLE (-1677 1125);
FORCEADD TAP..1
(-1675 1275);
FORCEPROP 3 LASTPIN (-1725 1275) SIG_NAME M_D_CPU1_SB_DQ<7>
J 0
(-1715 1285);
DISPLAY 0.659574 (-1715 1285);
PAINT MONO (-1715 1285);
DISPLAY INVISIBLE (-1715 1285);
FORCEPROP 1 LASTPIN (-1725 1275) BN 7
J 0
(-1737 1283);
DISPLAY 0.680851 (-1737 1283);
PAINT GREEN (-1737 1283);
FORCEPROP 2 LAST CDS_LIB standard
J 0
(-1675 1275);
PAINT MONO (-1675 1275);
DISPLAY INVISIBLE (-1675 1275);
FORCEPROP 1 LAST BODY_TYPE PLUMBING
J 0
(-1675 1325);
DISPLAY 0.872340 (-1675 1325);
PAINT GREEN (-1675 1325);
DISPLAY INVISIBLE (-1675 1325);
FORCEPROP 1 LAST HDL_TAP TRUE
J 0
(-1350 1150);
DISPLAY 0.872340 (-1350 1150);
DISPLAY INVISIBLE (-1350 1150);
FORCEPROP 1 LAST PATH I37
J 0
(-1677 1275);
DISPLAY 0.872340 (-1677 1275);
PAINT GREEN (-1677 1275);
DISPLAY INVISIBLE (-1677 1275);
FORCEADD TAP..1
(-1675 1325);
FORCEPROP 3 LASTPIN (-1725 1325) SIG_NAME M_D_CPU1_SB_DQ<8>
J 0
(-1715 1335);
DISPLAY 0.659574 (-1715 1335);
PAINT MONO (-1715 1335);
DISPLAY INVISIBLE (-1715 1335);
FORCEPROP 1 LASTPIN (-1725 1325) BN 8
J 0
(-1737 1333);
DISPLAY 0.680851 (-1737 1333);
PAINT GREEN (-1737 1333);
FORCEPROP 2 LAST CDS_LIB standard
J 0
(-1675 1325);
PAINT MONO (-1675 1325);
DISPLAY INVISIBLE (-1675 1325);
FORCEPROP 1 LAST BODY_TYPE PLUMBING
J 0
(-1675 1375);
DISPLAY 0.872340 (-1675 1375);
PAINT GREEN (-1675 1375);
DISPLAY INVISIBLE (-1675 1375);
FORCEPROP 1 LAST HDL_TAP TRUE
J 0
(-1350 1200);
DISPLAY 0.872340 (-1350 1200);
DISPLAY INVISIBLE (-1350 1200);
FORCEPROP 1 LAST PATH I38
J 0
(-1677 1325);
DISPLAY 0.872340 (-1677 1325);
PAINT GREEN (-1677 1325);
DISPLAY INVISIBLE (-1677 1325);
FORCEADD TAP..1
(-1675 1575);
FORCEPROP 3 LASTPIN (-1725 1575) SIG_NAME M_D_CPU1_SB_DQ<13>
J 0
(-1715 1585);
DISPLAY 0.659574 (-1715 1585);
PAINT MONO (-1715 1585);
DISPLAY INVISIBLE (-1715 1585);
FORCEPROP 1 LASTPIN (-1725 1575) BN 13
J 0
(-1737 1583);
DISPLAY 0.680851 (-1737 1583);
PAINT GREEN (-1737 1583);
FORCEPROP 2 LAST CDS_LIB standard
J 0
(-1675 1575);
PAINT MONO (-1675 1575);
DISPLAY INVISIBLE (-1675 1575);
FORCEPROP 1 LAST BODY_TYPE PLUMBING
J 0
(-1675 1625);
DISPLAY 0.872340 (-1675 1625);
PAINT GREEN (-1675 1625);
DISPLAY INVISIBLE (-1675 1625);
FORCEPROP 1 LAST HDL_TAP TRUE
J 0
(-1350 1450);
DISPLAY 0.872340 (-1350 1450);
DISPLAY INVISIBLE (-1350 1450);
FORCEPROP 1 LAST PATH I39
J 0
(-1677 1575);
DISPLAY 0.872340 (-1677 1575);
PAINT GREEN (-1677 1575);
DISPLAY INVISIBLE (-1677 1575);
FORCEADD OFFPAGE..2
R 2
(-4250 675);
FORCEPROP 2 LAST $XR0 54 
J 0
(-4474 675);
DISPLAY 0.638298 (-4474 675);
PAINT MONO (-4474 675);
FORCEPROP 2 LAST CDS_LIB standard
J 0
(-4250 675);
PAINT MONO (-4250 675);
DISPLAY INVISIBLE (-4250 675);
FORCEPROP 1 LAST OFFPAGE TRUE
J 2
(-4575 550);
DISPLAY 0.872340 (-4575 550);
DISPLAY INVISIBLE (-4575 550);
FORCEPROP 1 LAST COMMENT_BODY TRUE
J 2
(-4205 580);
DISPLAY 0.872340 (-4205 580);
PAINT GREEN (-4205 580);
DISPLAY INVISIBLE (-4205 580);
FORCEPROP 2 LAST PATH I4
J 0
(-4200 750);
DISPLAY 1.021277 (-4200 750);
DISPLAY INVISIBLE (-4200 750);
FORCEADD TAP..1
(-1675 1525);
FORCEPROP 3 LASTPIN (-1725 1525) SIG_NAME M_D_CPU1_SB_DQ<12>
J 0
(-1715 1535);
DISPLAY 0.659574 (-1715 1535);
PAINT MONO (-1715 1535);
DISPLAY INVISIBLE (-1715 1535);
FORCEPROP 1 LASTPIN (-1725 1525) BN 12
J 0
(-1737 1533);
DISPLAY 0.680851 (-1737 1533);
PAINT GREEN (-1737 1533);
FORCEPROP 2 LAST CDS_LIB standard
J 0
(-1675 1525);
PAINT MONO (-1675 1525);
DISPLAY INVISIBLE (-1675 1525);
FORCEPROP 1 LAST BODY_TYPE PLUMBING
J 0
(-1675 1575);
DISPLAY 0.872340 (-1675 1575);
PAINT GREEN (-1675 1575);
DISPLAY INVISIBLE (-1675 1575);
FORCEPROP 1 LAST HDL_TAP TRUE
J 0
(-1350 1400);
DISPLAY 0.872340 (-1350 1400);
DISPLAY INVISIBLE (-1350 1400);
FORCEPROP 1 LAST PATH I40
J 0
(-1677 1525);
DISPLAY 0.872340 (-1677 1525);
PAINT GREEN (-1677 1525);
DISPLAY INVISIBLE (-1677 1525);
FORCEADD TAP..1
(-1675 1425);
FORCEPROP 3 LASTPIN (-1725 1425) SIG_NAME M_D_CPU1_SB_DQ<10>
J 0
(-1715 1435);
DISPLAY 0.659574 (-1715 1435);
PAINT MONO (-1715 1435);
DISPLAY INVISIBLE (-1715 1435);
FORCEPROP 1 LASTPIN (-1725 1425) BN 10
J 0
(-1737 1433);
DISPLAY 0.680851 (-1737 1433);
PAINT GREEN (-1737 1433);
FORCEPROP 2 LAST CDS_LIB standard
J 0
(-1675 1425);
PAINT MONO (-1675 1425);
DISPLAY INVISIBLE (-1675 1425);
FORCEPROP 1 LAST BODY_TYPE PLUMBING
J 0
(-1675 1475);
DISPLAY 0.872340 (-1675 1475);
PAINT GREEN (-1675 1475);
DISPLAY INVISIBLE (-1675 1475);
FORCEPROP 1 LAST HDL_TAP TRUE
J 0
(-1350 1300);
DISPLAY 0.872340 (-1350 1300);
DISPLAY INVISIBLE (-1350 1300);
FORCEPROP 1 LAST PATH I41
J 0
(-1677 1425);
DISPLAY 0.872340 (-1677 1425);
PAINT GREEN (-1677 1425);
DISPLAY INVISIBLE (-1677 1425);
FORCEADD TAP..1
(-1675 1475);
FORCEPROP 3 LASTPIN (-1725 1475) SIG_NAME M_D_CPU1_SB_DQ<11>
J 0
(-1715 1485);
DISPLAY 0.659574 (-1715 1485);
PAINT MONO (-1715 1485);
DISPLAY INVISIBLE (-1715 1485);
FORCEPROP 1 LASTPIN (-1725 1475) BN 11
J 0
(-1737 1483);
DISPLAY 0.680851 (-1737 1483);
PAINT GREEN (-1737 1483);
FORCEPROP 2 LAST CDS_LIB standard
J 0
(-1675 1475);
PAINT MONO (-1675 1475);
DISPLAY INVISIBLE (-1675 1475);
FORCEPROP 1 LAST BODY_TYPE PLUMBING
J 0
(-1675 1525);
DISPLAY 0.872340 (-1675 1525);
PAINT GREEN (-1675 1525);
DISPLAY INVISIBLE (-1675 1525);
FORCEPROP 1 LAST HDL_TAP TRUE
J 0
(-1350 1350);
DISPLAY 0.872340 (-1350 1350);
DISPLAY INVISIBLE (-1350 1350);
FORCEPROP 1 LAST PATH I42
J 0
(-1677 1475);
DISPLAY 0.872340 (-1677 1475);
PAINT GREEN (-1677 1475);
DISPLAY INVISIBLE (-1677 1475);
FORCEADD TAP..1
(-1675 1375);
FORCEPROP 3 LASTPIN (-1725 1375) SIG_NAME M_D_CPU1_SB_DQ<9>
J 0
(-1715 1385);
DISPLAY 0.659574 (-1715 1385);
PAINT MONO (-1715 1385);
DISPLAY INVISIBLE (-1715 1385);
FORCEPROP 1 LASTPIN (-1725 1375) BN 9
J 0
(-1737 1383);
DISPLAY 0.680851 (-1737 1383);
PAINT GREEN (-1737 1383);
FORCEPROP 2 LAST CDS_LIB standard
J 0
(-1675 1375);
PAINT MONO (-1675 1375);
DISPLAY INVISIBLE (-1675 1375);
FORCEPROP 1 LAST BODY_TYPE PLUMBING
J 0
(-1675 1425);
DISPLAY 0.872340 (-1675 1425);
PAINT GREEN (-1675 1425);
DISPLAY INVISIBLE (-1675 1425);
FORCEPROP 1 LAST HDL_TAP TRUE
J 0
(-1350 1250);
DISPLAY 0.872340 (-1350 1250);
DISPLAY INVISIBLE (-1350 1250);
FORCEPROP 1 LAST PATH I43
J 0
(-1677 1375);
DISPLAY 0.872340 (-1677 1375);
PAINT GREEN (-1677 1375);
DISPLAY INVISIBLE (-1677 1375);
FORCEADD TAP..1
(-1675 1625);
FORCEPROP 3 LASTPIN (-1725 1625) SIG_NAME M_D_CPU1_SB_DQ<14>
J 0
(-1715 1635);
DISPLAY 0.659574 (-1715 1635);
PAINT MONO (-1715 1635);
DISPLAY INVISIBLE (-1715 1635);
FORCEPROP 1 LASTPIN (-1725 1625) BN 14
J 0
(-1737 1633);
DISPLAY 0.680851 (-1737 1633);
PAINT GREEN (-1737 1633);
FORCEPROP 2 LAST CDS_LIB standard
J 0
(-1675 1625);
PAINT MONO (-1675 1625);
DISPLAY INVISIBLE (-1675 1625);
FORCEPROP 1 LAST BODY_TYPE PLUMBING
J 0
(-1675 1675);
DISPLAY 0.872340 (-1675 1675);
PAINT GREEN (-1675 1675);
DISPLAY INVISIBLE (-1675 1675);
FORCEPROP 1 LAST HDL_TAP TRUE
J 0
(-1350 1500);
DISPLAY 0.872340 (-1350 1500);
DISPLAY INVISIBLE (-1350 1500);
FORCEPROP 1 LAST PATH I44
J 0
(-1677 1625);
DISPLAY 0.872340 (-1677 1625);
PAINT GREEN (-1677 1625);
DISPLAY INVISIBLE (-1677 1625);
FORCEADD TAP..1
(-1675 1675);
FORCEPROP 3 LASTPIN (-1725 1675) SIG_NAME M_D_CPU1_SB_DQ<15>
J 0
(-1715 1685);
DISPLAY 0.659574 (-1715 1685);
PAINT MONO (-1715 1685);
DISPLAY INVISIBLE (-1715 1685);
FORCEPROP 1 LASTPIN (-1725 1675) BN 15
J 0
(-1737 1683);
DISPLAY 0.680851 (-1737 1683);
PAINT GREEN (-1737 1683);
FORCEPROP 2 LAST CDS_LIB standard
J 0
(-1675 1675);
PAINT MONO (-1675 1675);
DISPLAY INVISIBLE (-1675 1675);
FORCEPROP 1 LAST BODY_TYPE PLUMBING
J 0
(-1675 1725);
DISPLAY 0.872340 (-1675 1725);
PAINT GREEN (-1675 1725);
DISPLAY INVISIBLE (-1675 1725);
FORCEPROP 1 LAST HDL_TAP TRUE
J 0
(-1350 1550);
DISPLAY 0.872340 (-1350 1550);
DISPLAY INVISIBLE (-1350 1550);
FORCEPROP 1 LAST PATH I45
J 0
(-1677 1675);
DISPLAY 0.872340 (-1677 1675);
PAINT GREEN (-1677 1675);
DISPLAY INVISIBLE (-1677 1675);
FORCEADD TAP..1
(-1675 1725);
FORCEPROP 3 LASTPIN (-1725 1725) SIG_NAME M_D_CPU1_SB_DQ<16>
J 0
(-1715 1735);
DISPLAY 0.659574 (-1715 1735);
PAINT MONO (-1715 1735);
DISPLAY INVISIBLE (-1715 1735);
FORCEPROP 1 LASTPIN (-1725 1725) BN 16
J 0
(-1737 1733);
DISPLAY 0.680851 (-1737 1733);
PAINT GREEN (-1737 1733);
FORCEPROP 2 LAST CDS_LIB standard
J 0
(-1675 1725);
PAINT MONO (-1675 1725);
DISPLAY INVISIBLE (-1675 1725);
FORCEPROP 1 LAST BODY_TYPE PLUMBING
J 0
(-1675 1775);
DISPLAY 0.872340 (-1675 1775);
PAINT GREEN (-1675 1775);
DISPLAY INVISIBLE (-1675 1775);
FORCEPROP 1 LAST HDL_TAP TRUE
J 0
(-1350 1600);
DISPLAY 0.872340 (-1350 1600);
DISPLAY INVISIBLE (-1350 1600);
FORCEPROP 1 LAST PATH I46
J 0
(-1677 1725);
DISPLAY 0.872340 (-1677 1725);
PAINT GREEN (-1677 1725);
DISPLAY INVISIBLE (-1677 1725);
FORCEADD TAP..1
(-1675 1825);
FORCEPROP 3 LASTPIN (-1725 1825) SIG_NAME M_D_CPU1_SB_DQ<18>
J 0
(-1715 1835);
DISPLAY 0.659574 (-1715 1835);
PAINT MONO (-1715 1835);
DISPLAY INVISIBLE (-1715 1835);
FORCEPROP 1 LASTPIN (-1725 1825) BN 18
J 0
(-1737 1833);
DISPLAY 0.680851 (-1737 1833);
PAINT GREEN (-1737 1833);
FORCEPROP 2 LAST CDS_LIB standard
J 0
(-1675 1825);
PAINT MONO (-1675 1825);
DISPLAY INVISIBLE (-1675 1825);
FORCEPROP 1 LAST BODY_TYPE PLUMBING
J 0
(-1675 1875);
DISPLAY 0.872340 (-1675 1875);
PAINT GREEN (-1675 1875);
DISPLAY INVISIBLE (-1675 1875);
FORCEPROP 1 LAST HDL_TAP TRUE
J 0
(-1350 1700);
DISPLAY 0.872340 (-1350 1700);
DISPLAY INVISIBLE (-1350 1700);
FORCEPROP 1 LAST PATH I47
J 0
(-1677 1825);
DISPLAY 0.872340 (-1677 1825);
PAINT GREEN (-1677 1825);
DISPLAY INVISIBLE (-1677 1825);
FORCEADD TAP..1
(-1675 1775);
FORCEPROP 3 LASTPIN (-1725 1775) SIG_NAME M_D_CPU1_SB_DQ<17>
J 0
(-1715 1785);
DISPLAY 0.659574 (-1715 1785);
PAINT MONO (-1715 1785);
DISPLAY INVISIBLE (-1715 1785);
FORCEPROP 1 LASTPIN (-1725 1775) BN 17
J 0
(-1737 1783);
DISPLAY 0.680851 (-1737 1783);
PAINT GREEN (-1737 1783);
FORCEPROP 2 LAST CDS_LIB standard
J 0
(-1675 1775);
PAINT MONO (-1675 1775);
DISPLAY INVISIBLE (-1675 1775);
FORCEPROP 1 LAST BODY_TYPE PLUMBING
J 0
(-1675 1825);
DISPLAY 0.872340 (-1675 1825);
PAINT GREEN (-1675 1825);
DISPLAY INVISIBLE (-1675 1825);
FORCEPROP 1 LAST HDL_TAP TRUE
J 0
(-1350 1650);
DISPLAY 0.872340 (-1350 1650);
DISPLAY INVISIBLE (-1350 1650);
FORCEPROP 1 LAST PATH I48
J 0
(-1677 1775);
DISPLAY 0.872340 (-1677 1775);
PAINT GREEN (-1677 1775);
DISPLAY INVISIBLE (-1677 1775);
FORCEADD TAP..1
(-1675 2075);
FORCEPROP 3 LASTPIN (-1725 2075) SIG_NAME M_D_CPU1_SB_DQ<23>
J 0
(-1715 2085);
DISPLAY 0.659574 (-1715 2085);
PAINT MONO (-1715 2085);
DISPLAY INVISIBLE (-1715 2085);
FORCEPROP 1 LASTPIN (-1725 2075) BN 23
J 0
(-1737 2083);
DISPLAY 0.680851 (-1737 2083);
PAINT GREEN (-1737 2083);
FORCEPROP 2 LAST CDS_LIB standard
J 0
(-1675 2075);
DISPLAY INVISIBLE (-1675 2075);
FORCEPROP 1 LAST BODY_TYPE PLUMBING
J 0
(-1675 2125);
DISPLAY 0.872340 (-1675 2125);
PAINT GREEN (-1675 2125);
DISPLAY INVISIBLE (-1675 2125);
FORCEPROP 1 LAST HDL_TAP TRUE
J 0
(-1350 1950);
DISPLAY 0.872340 (-1350 1950);
DISPLAY INVISIBLE (-1350 1950);
FORCEPROP 1 LAST PATH I49
J 0
(-1677 2075);
DISPLAY 0.872340 (-1677 2075);
PAINT GREEN (-1677 2075);
DISPLAY INVISIBLE (-1677 2075);
FORCEADD OFFPAGE..2
R 2
(-4250 725);
FORCEPROP 2 LAST $XR0 54 
J 0
(-4474 725);
DISPLAY 0.638298 (-4474 725);
PAINT MONO (-4474 725);
FORCEPROP 2 LAST CDS_LIB standard
J 0
(-4250 725);
PAINT MONO (-4250 725);
DISPLAY INVISIBLE (-4250 725);
FORCEPROP 1 LAST OFFPAGE TRUE
J 2
(-4575 600);
DISPLAY 0.872340 (-4575 600);
DISPLAY INVISIBLE (-4575 600);
FORCEPROP 1 LAST COMMENT_BODY TRUE
J 2
(-4205 630);
DISPLAY 0.872340 (-4205 630);
PAINT GREEN (-4205 630);
DISPLAY INVISIBLE (-4205 630);
FORCEPROP 2 LAST PATH I5
J 0
(-4200 800);
DISPLAY 1.021277 (-4200 800);
DISPLAY INVISIBLE (-4200 800);
FORCEADD TAP..1
(-1675 2025);
FORCEPROP 3 LASTPIN (-1725 2025) SIG_NAME M_D_CPU1_SB_DQ<22>
J 0
(-1715 2035);
DISPLAY 0.659574 (-1715 2035);
PAINT MONO (-1715 2035);
DISPLAY INVISIBLE (-1715 2035);
FORCEPROP 1 LASTPIN (-1725 2025) BN 22
J 0
(-1737 2033);
DISPLAY 0.680851 (-1737 2033);
PAINT GREEN (-1737 2033);
FORCEPROP 2 LAST CDS_LIB standard
J 0
(-1675 2025);
DISPLAY INVISIBLE (-1675 2025);
FORCEPROP 1 LAST BODY_TYPE PLUMBING
J 0
(-1675 2075);
DISPLAY 0.872340 (-1675 2075);
PAINT GREEN (-1675 2075);
DISPLAY INVISIBLE (-1675 2075);
FORCEPROP 1 LAST HDL_TAP TRUE
J 0
(-1350 1900);
DISPLAY 0.872340 (-1350 1900);
DISPLAY INVISIBLE (-1350 1900);
FORCEPROP 1 LAST PATH I50
J 0
(-1677 2025);
DISPLAY 0.872340 (-1677 2025);
PAINT GREEN (-1677 2025);
DISPLAY INVISIBLE (-1677 2025);
FORCEADD TAP..1
(-1675 1925);
FORCEPROP 3 LASTPIN (-1725 1925) SIG_NAME M_D_CPU1_SB_DQ<20>
J 0
(-1715 1935);
DISPLAY 0.659574 (-1715 1935);
PAINT MONO (-1715 1935);
DISPLAY INVISIBLE (-1715 1935);
FORCEPROP 1 LASTPIN (-1725 1925) BN 20
J 0
(-1737 1933);
DISPLAY 0.680851 (-1737 1933);
PAINT GREEN (-1737 1933);
FORCEPROP 2 LAST CDS_LIB standard
J 0
(-1675 1925);
PAINT MONO (-1675 1925);
DISPLAY INVISIBLE (-1675 1925);
FORCEPROP 1 LAST BODY_TYPE PLUMBING
J 0
(-1675 1975);
DISPLAY 0.872340 (-1675 1975);
PAINT GREEN (-1675 1975);
DISPLAY INVISIBLE (-1675 1975);
FORCEPROP 1 LAST HDL_TAP TRUE
J 0
(-1350 1800);
DISPLAY 0.872340 (-1350 1800);
DISPLAY INVISIBLE (-1350 1800);
FORCEPROP 1 LAST PATH I51
J 0
(-1677 1925);
DISPLAY 0.872340 (-1677 1925);
PAINT GREEN (-1677 1925);
DISPLAY INVISIBLE (-1677 1925);
FORCEADD TAP..1
(-1675 1975);
FORCEPROP 3 LASTPIN (-1725 1975) SIG_NAME M_D_CPU1_SB_DQ<21>
J 0
(-1715 1985);
DISPLAY 0.659574 (-1715 1985);
PAINT MONO (-1715 1985);
DISPLAY INVISIBLE (-1715 1985);
FORCEPROP 1 LASTPIN (-1725 1975) BN 21
J 0
(-1737 1983);
DISPLAY 0.680851 (-1737 1983);
PAINT GREEN (-1737 1983);
FORCEPROP 2 LAST CDS_LIB standard
J 0
(-1675 1975);
PAINT MONO (-1675 1975);
DISPLAY INVISIBLE (-1675 1975);
FORCEPROP 1 LAST BODY_TYPE PLUMBING
J 0
(-1675 2025);
DISPLAY 0.872340 (-1675 2025);
PAINT GREEN (-1675 2025);
DISPLAY INVISIBLE (-1675 2025);
FORCEPROP 1 LAST HDL_TAP TRUE
J 0
(-1350 1850);
DISPLAY 0.872340 (-1350 1850);
DISPLAY INVISIBLE (-1350 1850);
FORCEPROP 1 LAST PATH I52
J 0
(-1677 1975);
DISPLAY 0.872340 (-1677 1975);
PAINT GREEN (-1677 1975);
DISPLAY INVISIBLE (-1677 1975);
FORCEADD TAP..1
(-1675 1875);
FORCEPROP 3 LASTPIN (-1725 1875) SIG_NAME M_D_CPU1_SB_DQ<19>
J 0
(-1715 1885);
DISPLAY 0.659574 (-1715 1885);
PAINT MONO (-1715 1885);
DISPLAY INVISIBLE (-1715 1885);
FORCEPROP 1 LASTPIN (-1725 1875) BN 19
J 0
(-1737 1883);
DISPLAY 0.680851 (-1737 1883);
PAINT GREEN (-1737 1883);
FORCEPROP 2 LAST CDS_LIB standard
J 0
(-1675 1875);
PAINT MONO (-1675 1875);
DISPLAY INVISIBLE (-1675 1875);
FORCEPROP 1 LAST BODY_TYPE PLUMBING
J 0
(-1675 1925);
DISPLAY 0.872340 (-1675 1925);
PAINT GREEN (-1675 1925);
DISPLAY INVISIBLE (-1675 1925);
FORCEPROP 1 LAST HDL_TAP TRUE
J 0
(-1350 1750);
DISPLAY 0.872340 (-1350 1750);
DISPLAY INVISIBLE (-1350 1750);
FORCEPROP 1 LAST PATH I53
J 0
(-1677 1875);
DISPLAY 0.872340 (-1677 1875);
PAINT GREEN (-1677 1875);
DISPLAY INVISIBLE (-1677 1875);
FORCEADD TAP..1
R 2
(-3325 2225);
FORCEPROP 3 LASTPIN (-3275 2225) SIG_NAME M_D_CPU1_SB_CB<6>
J 0
(-3265 2235);
DISPLAY 0.659574 (-3265 2235);
PAINT MONO (-3265 2235);
DISPLAY INVISIBLE (-3265 2235);
FORCEPROP 1 LASTPIN (-3275 2225) BN 6
J 2
(-3263 2233);
DISPLAY 0.680851 (-3263 2233);
PAINT GREEN (-3263 2233);
FORCEPROP 2 LAST CDS_LIB standard
J 0
(-3325 2225);
DISPLAY INVISIBLE (-3325 2225);
FORCEPROP 1 LAST BODY_TYPE PLUMBING
J 2
(-3325 2275);
DISPLAY 0.872340 (-3325 2275);
PAINT GREEN (-3325 2275);
DISPLAY INVISIBLE (-3325 2275);
FORCEPROP 1 LAST HDL_TAP TRUE
J 2
(-3650 2100);
DISPLAY 0.872340 (-3650 2100);
DISPLAY INVISIBLE (-3650 2100);
FORCEPROP 1 LAST PATH I54
J 2
(-3323 2225);
DISPLAY 0.872340 (-3323 2225);
PAINT GREEN (-3323 2225);
DISPLAY INVISIBLE (-3323 2225);
FORCEADD TAP..1
R 2
(-3325 2275);
FORCEPROP 3 LASTPIN (-3275 2275) SIG_NAME M_D_CPU1_SB_CB<7>
J 0
(-3265 2285);
DISPLAY 0.659574 (-3265 2285);
PAINT MONO (-3265 2285);
DISPLAY INVISIBLE (-3265 2285);
FORCEPROP 1 LASTPIN (-3275 2275) BN 7
J 2
(-3263 2283);
DISPLAY 0.680851 (-3263 2283);
PAINT GREEN (-3263 2283);
FORCEPROP 2 LAST CDS_LIB standard
J 0
(-3325 2275);
DISPLAY INVISIBLE (-3325 2275);
FORCEPROP 1 LAST BODY_TYPE PLUMBING
J 2
(-3325 2325);
DISPLAY 0.872340 (-3325 2325);
PAINT GREEN (-3325 2325);
DISPLAY INVISIBLE (-3325 2325);
FORCEPROP 1 LAST HDL_TAP TRUE
J 2
(-3650 2150);
DISPLAY 0.872340 (-3650 2150);
DISPLAY INVISIBLE (-3650 2150);
FORCEPROP 1 LAST PATH I55
J 2
(-3323 2275);
DISPLAY 0.872340 (-3323 2275);
PAINT GREEN (-3323 2275);
DISPLAY INVISIBLE (-3323 2275);
FORCEADD TAP..1
R 2
(-3325 2175);
FORCEPROP 3 LASTPIN (-3275 2175) SIG_NAME M_D_CPU1_SB_CB<5>
J 0
(-3265 2185);
DISPLAY 0.659574 (-3265 2185);
PAINT MONO (-3265 2185);
DISPLAY INVISIBLE (-3265 2185);
FORCEPROP 1 LASTPIN (-3275 2175) BN 5
J 2
(-3263 2183);
DISPLAY 0.680851 (-3263 2183);
PAINT GREEN (-3263 2183);
FORCEPROP 2 LAST CDS_LIB standard
J 0
(-3325 2175);
DISPLAY INVISIBLE (-3325 2175);
FORCEPROP 1 LAST BODY_TYPE PLUMBING
J 2
(-3325 2225);
DISPLAY 0.872340 (-3325 2225);
PAINT GREEN (-3325 2225);
DISPLAY INVISIBLE (-3325 2225);
FORCEPROP 1 LAST HDL_TAP TRUE
J 2
(-3650 2050);
DISPLAY 0.872340 (-3650 2050);
DISPLAY INVISIBLE (-3650 2050);
FORCEPROP 1 LAST PATH I56
J 2
(-3323 2175);
DISPLAY 0.872340 (-3323 2175);
PAINT GREEN (-3323 2175);
DISPLAY INVISIBLE (-3323 2175);
FORCEADD TAP..1
R 2
(-3325 2125);
FORCEPROP 3 LASTPIN (-3275 2125) SIG_NAME M_D_CPU1_SB_CB<4>
J 0
(-3265 2135);
DISPLAY 0.659574 (-3265 2135);
PAINT MONO (-3265 2135);
DISPLAY INVISIBLE (-3265 2135);
FORCEPROP 1 LASTPIN (-3275 2125) BN 4
J 2
(-3263 2133);
DISPLAY 0.680851 (-3263 2133);
PAINT GREEN (-3263 2133);
FORCEPROP 2 LAST CDS_LIB standard
J 0
(-3325 2125);
DISPLAY INVISIBLE (-3325 2125);
FORCEPROP 1 LAST BODY_TYPE PLUMBING
J 2
(-3325 2175);
DISPLAY 0.872340 (-3325 2175);
PAINT GREEN (-3325 2175);
DISPLAY INVISIBLE (-3325 2175);
FORCEPROP 1 LAST HDL_TAP TRUE
J 2
(-3650 2000);
DISPLAY 0.872340 (-3650 2000);
DISPLAY INVISIBLE (-3650 2000);
FORCEPROP 1 LAST PATH I57
J 2
(-3323 2125);
DISPLAY 0.872340 (-3323 2125);
PAINT GREEN (-3323 2125);
DISPLAY INVISIBLE (-3323 2125);
FORCEADD TAP..1
R 2
(-3325 2375);
FORCEPROP 3 LASTPIN (-3275 2375) SIG_NAME M_D_CPU1_SA_CB<0>
J 0
(-3265 2385);
DISPLAY 0.659574 (-3265 2385);
PAINT MONO (-3265 2385);
DISPLAY INVISIBLE (-3265 2385);
FORCEPROP 1 LASTPIN (-3275 2375) BN 0
J 2
(-3263 2383);
DISPLAY 0.680851 (-3263 2383);
PAINT GREEN (-3263 2383);
FORCEPROP 2 LAST CDS_LIB standard
J 0
(-3325 2375);
PAINT MONO (-3325 2375);
DISPLAY INVISIBLE (-3325 2375);
FORCEPROP 1 LAST BODY_TYPE PLUMBING
J 2
(-3325 2425);
DISPLAY 0.872340 (-3325 2425);
PAINT GREEN (-3325 2425);
DISPLAY INVISIBLE (-3325 2425);
FORCEPROP 1 LAST HDL_TAP TRUE
J 2
(-3650 2250);
DISPLAY 0.872340 (-3650 2250);
DISPLAY INVISIBLE (-3650 2250);
FORCEPROP 1 LAST PATH I58
J 2
(-3323 2375);
DISPLAY 0.872340 (-3323 2375);
PAINT GREEN (-3323 2375);
DISPLAY INVISIBLE (-3323 2375);
FORCEADD TAP..1
R 2
(-3325 2475);
FORCEPROP 3 LASTPIN (-3275 2475) SIG_NAME M_D_CPU1_SA_CB<2>
J 0
(-3265 2485);
DISPLAY 0.659574 (-3265 2485);
PAINT MONO (-3265 2485);
DISPLAY INVISIBLE (-3265 2485);
FORCEPROP 1 LASTPIN (-3275 2475) BN 2
J 2
(-3263 2483);
DISPLAY 0.680851 (-3263 2483);
PAINT GREEN (-3263 2483);
FORCEPROP 2 LAST CDS_LIB standard
J 0
(-3325 2475);
DISPLAY INVISIBLE (-3325 2475);
FORCEPROP 1 LAST BODY_TYPE PLUMBING
J 2
(-3325 2525);
DISPLAY 0.872340 (-3325 2525);
PAINT GREEN (-3325 2525);
DISPLAY INVISIBLE (-3325 2525);
FORCEPROP 1 LAST HDL_TAP TRUE
J 2
(-3650 2350);
DISPLAY 0.872340 (-3650 2350);
DISPLAY INVISIBLE (-3650 2350);
FORCEPROP 1 LAST PATH I59
J 2
(-3323 2475);
DISPLAY 0.872340 (-3323 2475);
PAINT GREEN (-3323 2475);
DISPLAY INVISIBLE (-3323 2475);
FORCEADD OFFPAGE..3
R 2
(-4250 1275);
FORCEPROP 2 LAST $XR0 114 
J 0
(-4530 1275);
DISPLAY 0.638298 (-4530 1275);
PAINT MONO (-4530 1275);
FORCEPROP 2 LAST CDS_LIB standard
J 0
(-4250 1275);
PAINT MONO (-4250 1275);
DISPLAY INVISIBLE (-4250 1275);
FORCEPROP 1 LAST OFFPAGE TRUE
J 2
(-4575 1150);
DISPLAY 0.872340 (-4575 1150);
DISPLAY INVISIBLE (-4575 1150);
FORCEPROP 1 LAST COMMENT_BODY TRUE
J 2
(-4200 1175);
DISPLAY 0.872340 (-4200 1175);
PAINT GREEN (-4200 1175);
DISPLAY INVISIBLE (-4200 1175);
FORCEPROP 2 LAST PATH I6
J 0
(-4200 1350);
DISPLAY 1.021277 (-4200 1350);
DISPLAY INVISIBLE (-4200 1350);
FORCEADD TAP..1
R 2
(-3325 2425);
FORCEPROP 3 LASTPIN (-3275 2425) SIG_NAME M_D_CPU1_SA_CB<1>
J 0
(-3265 2435);
DISPLAY 0.659574 (-3265 2435);
PAINT MONO (-3265 2435);
DISPLAY INVISIBLE (-3265 2435);
FORCEPROP 1 LASTPIN (-3275 2425) BN 1
J 2
(-3263 2433);
DISPLAY 0.680851 (-3263 2433);
PAINT GREEN (-3263 2433);
FORCEPROP 2 LAST CDS_LIB standard
J 0
(-3325 2425);
DISPLAY INVISIBLE (-3325 2425);
FORCEPROP 1 LAST BODY_TYPE PLUMBING
J 2
(-3325 2475);
DISPLAY 0.872340 (-3325 2475);
PAINT GREEN (-3325 2475);
DISPLAY INVISIBLE (-3325 2475);
FORCEPROP 1 LAST HDL_TAP TRUE
J 2
(-3650 2300);
DISPLAY 0.872340 (-3650 2300);
DISPLAY INVISIBLE (-3650 2300);
FORCEPROP 1 LAST PATH I60
J 2
(-3323 2425);
DISPLAY 0.872340 (-3323 2425);
PAINT GREEN (-3323 2425);
DISPLAY INVISIBLE (-3323 2425);
FORCEADD TAP..1
R 2
(-3325 2575);
FORCEPROP 3 LASTPIN (-3275 2575) SIG_NAME M_D_CPU1_SA_CB<4>
J 0
(-3265 2585);
DISPLAY 0.659574 (-3265 2585);
PAINT MONO (-3265 2585);
DISPLAY INVISIBLE (-3265 2585);
FORCEPROP 1 LASTPIN (-3275 2575) BN 4
J 2
(-3263 2583);
DISPLAY 0.680851 (-3263 2583);
PAINT GREEN (-3263 2583);
FORCEPROP 2 LAST CDS_LIB standard
J 0
(-3325 2575);
DISPLAY INVISIBLE (-3325 2575);
FORCEPROP 1 LAST BODY_TYPE PLUMBING
J 2
(-3325 2625);
DISPLAY 0.872340 (-3325 2625);
PAINT GREEN (-3325 2625);
DISPLAY INVISIBLE (-3325 2625);
FORCEPROP 1 LAST HDL_TAP TRUE
J 2
(-3650 2450);
DISPLAY 0.872340 (-3650 2450);
DISPLAY INVISIBLE (-3650 2450);
FORCEPROP 1 LAST PATH I61
J 2
(-3323 2575);
DISPLAY 0.872340 (-3323 2575);
PAINT GREEN (-3323 2575);
DISPLAY INVISIBLE (-3323 2575);
FORCEADD TAP..1
R 2
(-3325 2525);
FORCEPROP 3 LASTPIN (-3275 2525) SIG_NAME M_D_CPU1_SA_CB<3>
J 0
(-3265 2535);
DISPLAY 0.659574 (-3265 2535);
PAINT MONO (-3265 2535);
DISPLAY INVISIBLE (-3265 2535);
FORCEPROP 1 LASTPIN (-3275 2525) BN 3
J 2
(-3263 2533);
DISPLAY 0.680851 (-3263 2533);
PAINT GREEN (-3263 2533);
FORCEPROP 2 LAST CDS_LIB standard
J 0
(-3325 2525);
DISPLAY INVISIBLE (-3325 2525);
FORCEPROP 1 LAST BODY_TYPE PLUMBING
J 2
(-3325 2575);
DISPLAY 0.872340 (-3325 2575);
PAINT GREEN (-3325 2575);
DISPLAY INVISIBLE (-3325 2575);
FORCEPROP 1 LAST HDL_TAP TRUE
J 2
(-3650 2400);
DISPLAY 0.872340 (-3650 2400);
DISPLAY INVISIBLE (-3650 2400);
FORCEPROP 1 LAST PATH I62
J 2
(-3323 2525);
DISPLAY 0.872340 (-3323 2525);
PAINT GREEN (-3323 2525);
DISPLAY INVISIBLE (-3323 2525);
FORCEADD TAP..1
R 2
(-3325 2625);
FORCEPROP 3 LASTPIN (-3275 2625) SIG_NAME M_D_CPU1_SA_CB<5>
J 0
(-3265 2635);
DISPLAY 0.659574 (-3265 2635);
PAINT MONO (-3265 2635);
DISPLAY INVISIBLE (-3265 2635);
FORCEPROP 1 LASTPIN (-3275 2625) BN 5
J 2
(-3263 2633);
DISPLAY 0.680851 (-3263 2633);
PAINT GREEN (-3263 2633);
FORCEPROP 2 LAST CDS_LIB standard
J 0
(-3325 2625);
DISPLAY INVISIBLE (-3325 2625);
FORCEPROP 1 LAST BODY_TYPE PLUMBING
J 2
(-3325 2675);
DISPLAY 0.872340 (-3325 2675);
PAINT GREEN (-3325 2675);
DISPLAY INVISIBLE (-3325 2675);
FORCEPROP 1 LAST HDL_TAP TRUE
J 2
(-3650 2500);
DISPLAY 0.872340 (-3650 2500);
DISPLAY INVISIBLE (-3650 2500);
FORCEPROP 1 LAST PATH I63
J 2
(-3323 2625);
DISPLAY 0.872340 (-3323 2625);
PAINT GREEN (-3323 2625);
DISPLAY INVISIBLE (-3323 2625);
FORCEADD TAP..1
R 2
(-3325 2675);
FORCEPROP 3 LASTPIN (-3275 2675) SIG_NAME M_D_CPU1_SA_CB<6>
J 0
(-3265 2685);
DISPLAY 0.659574 (-3265 2685);
PAINT MONO (-3265 2685);
DISPLAY INVISIBLE (-3265 2685);
FORCEPROP 1 LASTPIN (-3275 2675) BN 6
J 2
(-3263 2683);
DISPLAY 0.680851 (-3263 2683);
PAINT GREEN (-3263 2683);
FORCEPROP 2 LAST CDS_LIB standard
J 0
(-3325 2675);
DISPLAY INVISIBLE (-3325 2675);
FORCEPROP 1 LAST BODY_TYPE PLUMBING
J 2
(-3325 2725);
DISPLAY 0.872340 (-3325 2725);
PAINT GREEN (-3325 2725);
DISPLAY INVISIBLE (-3325 2725);
FORCEPROP 1 LAST HDL_TAP TRUE
J 2
(-3650 2550);
DISPLAY 0.872340 (-3650 2550);
DISPLAY INVISIBLE (-3650 2550);
FORCEPROP 1 LAST PATH I64
J 2
(-3323 2675);
DISPLAY 0.872340 (-3323 2675);
PAINT GREEN (-3323 2675);
DISPLAY INVISIBLE (-3323 2675);
FORCEADD TAP..1
R 2
(-3325 2725);
FORCEPROP 3 LASTPIN (-3275 2725) SIG_NAME M_D_CPU1_SA_CB<7>
J 0
(-3265 2735);
DISPLAY 0.659574 (-3265 2735);
PAINT MONO (-3265 2735);
DISPLAY INVISIBLE (-3265 2735);
FORCEPROP 1 LASTPIN (-3275 2725) BN 7
J 2
(-3263 2733);
DISPLAY 0.680851 (-3263 2733);
PAINT GREEN (-3263 2733);
FORCEPROP 2 LAST CDS_LIB standard
J 0
(-3325 2725);
DISPLAY INVISIBLE (-3325 2725);
FORCEPROP 1 LAST BODY_TYPE PLUMBING
J 2
(-3325 2775);
DISPLAY 0.872340 (-3325 2775);
PAINT GREEN (-3325 2775);
DISPLAY INVISIBLE (-3325 2775);
FORCEPROP 1 LAST HDL_TAP TRUE
J 2
(-3650 2600);
DISPLAY 0.872340 (-3650 2600);
DISPLAY INVISIBLE (-3650 2600);
FORCEPROP 1 LAST PATH I65
J 2
(-3323 2725);
DISPLAY 0.872340 (-3323 2725);
PAINT GREEN (-3323 2725);
DISPLAY INVISIBLE (-3323 2725);
FORCEADD TAP..1
R 2
(-3325 3425);
FORCEPROP 3 LASTPIN (-3275 3425) SIG_NAME M_D_CPU1_SB_CA<0>
J 0
(-3265 3435);
DISPLAY 0.659574 (-3265 3435);
PAINT MONO (-3265 3435);
DISPLAY INVISIBLE (-3265 3435);
FORCEPROP 1 LASTPIN (-3275 3425) BN 0
J 2
(-3263 3433);
DISPLAY 0.680851 (-3263 3433);
PAINT GREEN (-3263 3433);
FORCEPROP 2 LAST CDS_LIB standard
J 0
(-3325 3425);
DISPLAY INVISIBLE (-3325 3425);
FORCEPROP 1 LAST BODY_TYPE PLUMBING
J 2
(-3325 3475);
DISPLAY 0.872340 (-3325 3475);
PAINT GREEN (-3325 3475);
DISPLAY INVISIBLE (-3325 3475);
FORCEPROP 1 LAST HDL_TAP TRUE
J 2
(-3650 3300);
DISPLAY 0.872340 (-3650 3300);
DISPLAY INVISIBLE (-3650 3300);
FORCEPROP 1 LAST PATH I66
J 2
(-3323 3425);
DISPLAY 0.872340 (-3323 3425);
PAINT GREEN (-3323 3425);
DISPLAY INVISIBLE (-3323 3425);
FORCEADD TAP..1
R 2
(-3325 3475);
FORCEPROP 3 LASTPIN (-3275 3475) SIG_NAME M_D_CPU1_SB_CA<1>
J 0
(-3265 3485);
DISPLAY 0.659574 (-3265 3485);
PAINT MONO (-3265 3485);
DISPLAY INVISIBLE (-3265 3485);
FORCEPROP 1 LASTPIN (-3275 3475) BN 1
J 2
(-3263 3483);
DISPLAY 0.680851 (-3263 3483);
PAINT GREEN (-3263 3483);
FORCEPROP 2 LAST CDS_LIB standard
J 0
(-3325 3475);
DISPLAY INVISIBLE (-3325 3475);
FORCEPROP 1 LAST BODY_TYPE PLUMBING
J 2
(-3325 3525);
DISPLAY 0.872340 (-3325 3525);
PAINT GREEN (-3325 3525);
DISPLAY INVISIBLE (-3325 3525);
FORCEPROP 1 LAST HDL_TAP TRUE
J 2
(-3650 3350);
DISPLAY 0.872340 (-3650 3350);
DISPLAY INVISIBLE (-3650 3350);
FORCEPROP 1 LAST PATH I67
J 2
(-3323 3475);
DISPLAY 0.872340 (-3323 3475);
PAINT GREEN (-3323 3475);
DISPLAY INVISIBLE (-3323 3475);
FORCEADD TAP..1
R 2
(-3325 3525);
FORCEPROP 3 LASTPIN (-3275 3525) SIG_NAME M_D_CPU1_SB_CA<2>
J 0
(-3265 3535);
DISPLAY 0.659574 (-3265 3535);
PAINT MONO (-3265 3535);
DISPLAY INVISIBLE (-3265 3535);
FORCEPROP 1 LASTPIN (-3275 3525) BN 2
J 2
(-3263 3533);
DISPLAY 0.680851 (-3263 3533);
PAINT GREEN (-3263 3533);
FORCEPROP 2 LAST CDS_LIB standard
J 0
(-3325 3525);
DISPLAY INVISIBLE (-3325 3525);
FORCEPROP 1 LAST BODY_TYPE PLUMBING
J 2
(-3325 3575);
DISPLAY 0.872340 (-3325 3575);
PAINT GREEN (-3325 3575);
DISPLAY INVISIBLE (-3325 3575);
FORCEPROP 1 LAST HDL_TAP TRUE
J 2
(-3650 3400);
DISPLAY 0.872340 (-3650 3400);
DISPLAY INVISIBLE (-3650 3400);
FORCEPROP 1 LAST PATH I68
J 2
(-3323 3525);
DISPLAY 0.872340 (-3323 3525);
PAINT GREEN (-3323 3525);
DISPLAY INVISIBLE (-3323 3525);
FORCEADD TAP..1
R 2
(-3325 3575);
FORCEPROP 3 LASTPIN (-3275 3575) SIG_NAME M_D_CPU1_SB_CA<3>
J 0
(-3265 3585);
DISPLAY 0.659574 (-3265 3585);
PAINT MONO (-3265 3585);
DISPLAY INVISIBLE (-3265 3585);
FORCEPROP 1 LASTPIN (-3275 3575) BN 3
J 2
(-3263 3583);
DISPLAY 0.680851 (-3263 3583);
PAINT GREEN (-3263 3583);
FORCEPROP 2 LAST CDS_LIB standard
J 0
(-3325 3575);
DISPLAY INVISIBLE (-3325 3575);
FORCEPROP 1 LAST BODY_TYPE PLUMBING
J 2
(-3325 3625);
DISPLAY 0.872340 (-3325 3625);
PAINT GREEN (-3325 3625);
DISPLAY INVISIBLE (-3325 3625);
FORCEPROP 1 LAST HDL_TAP TRUE
J 2
(-3650 3450);
DISPLAY 0.872340 (-3650 3450);
DISPLAY INVISIBLE (-3650 3450);
FORCEPROP 1 LAST PATH I69
J 2
(-3323 3575);
DISPLAY 0.872340 (-3323 3575);
PAINT GREEN (-3323 3575);
DISPLAY INVISIBLE (-3323 3575);
FORCEADD OFFPAGE..1
(-4175 1575);
FORCEPROP 2 LAST $XR7 105 
J 0
(-4577 1611);
DISPLAY 0.638298 (-4577 1611);
PAINT MONO (-4577 1611);
FORCEPROP 2 LAST $XR6 103 
J 0
(-4457 1611);
DISPLAY 0.638298 (-4457 1611);
PAINT MONO (-4457 1611);
FORCEPROP 2 LAST $XR5 102 
J 0
(-4697 1539);
DISPLAY 0.638298 (-4697 1539);
PAINT MONO (-4697 1539);
FORCEPROP 2 LAST $XR4 101 
J 0
(-4577 1539);
DISPLAY 0.638298 (-4577 1539);
PAINT MONO (-4577 1539);
FORCEPROP 2 LAST $XR3 100 
J 0
(-4457 1539);
DISPLAY 0.638298 (-4457 1539);
PAINT MONO (-4457 1539);
FORCEPROP 2 LAST $XR2 99 
J 0
(-4637 1575);
DISPLAY 0.638298 (-4637 1575);
PAINT MONO (-4637 1575);
FORCEPROP 2 LAST $XR1 98 
J 0
(-4547 1575);
DISPLAY 0.638298 (-4547 1575);
PAINT MONO (-4547 1575);
FORCEPROP 2 LAST $XR0 230 
J 0
(-4457 1575);
DISPLAY 0.638298 (-4457 1575);
PAINT MONO (-4457 1575);
FORCEPROP 2 LAST CDS_LIB standard
J 0
(-4175 1575);
PAINT MONO (-4175 1575);
DISPLAY INVISIBLE (-4175 1575);
FORCEPROP 1 LAST OFFPAGE TRUE
J 0
(-3850 1450);
DISPLAY 0.872340 (-3850 1450);
DISPLAY INVISIBLE (-3850 1450);
FORCEPROP 1 LAST COMMENT_BODY TRUE
J 0
(-4050 1475);
DISPLAY 0.872340 (-4050 1475);
PAINT GREEN (-4050 1475);
DISPLAY INVISIBLE (-4050 1475);
FORCEPROP 2 LAST PATH I7
J 0
(-4125 1650);
DISPLAY 1.021277 (-4125 1650);
DISPLAY INVISIBLE (-4125 1650);
FORCEADD TAP..1
R 2
(-3325 3625);
FORCEPROP 3 LASTPIN (-3275 3625) SIG_NAME M_D_CPU1_SB_CA<4>
J 0
(-3265 3635);
DISPLAY 0.659574 (-3265 3635);
PAINT MONO (-3265 3635);
DISPLAY INVISIBLE (-3265 3635);
FORCEPROP 1 LASTPIN (-3275 3625) BN 4
J 2
(-3263 3633);
DISPLAY 0.680851 (-3263 3633);
PAINT GREEN (-3263 3633);
FORCEPROP 2 LAST CDS_LIB standard
J 0
(-3325 3625);
DISPLAY INVISIBLE (-3325 3625);
FORCEPROP 1 LAST BODY_TYPE PLUMBING
J 2
(-3325 3675);
DISPLAY 0.872340 (-3325 3675);
PAINT GREEN (-3325 3675);
DISPLAY INVISIBLE (-3325 3675);
FORCEPROP 1 LAST HDL_TAP TRUE
J 2
(-3650 3500);
DISPLAY 0.872340 (-3650 3500);
DISPLAY INVISIBLE (-3650 3500);
FORCEPROP 1 LAST PATH I70
J 2
(-3323 3625);
DISPLAY 0.872340 (-3323 3625);
PAINT GREEN (-3323 3625);
DISPLAY INVISIBLE (-3323 3625);
FORCEADD TAP..1
R 2
(-3325 3725);
FORCEPROP 3 LASTPIN (-3275 3725) SIG_NAME M_D_CPU1_SB_CA<6>
J 0
(-3265 3735);
DISPLAY 0.659574 (-3265 3735);
PAINT MONO (-3265 3735);
DISPLAY INVISIBLE (-3265 3735);
FORCEPROP 1 LASTPIN (-3275 3725) BN 6
J 2
(-3263 3733);
DISPLAY 0.680851 (-3263 3733);
PAINT GREEN (-3263 3733);
FORCEPROP 2 LAST CDS_LIB standard
J 0
(-3325 3725);
DISPLAY INVISIBLE (-3325 3725);
FORCEPROP 1 LAST BODY_TYPE PLUMBING
J 2
(-3325 3775);
DISPLAY 0.872340 (-3325 3775);
PAINT GREEN (-3325 3775);
DISPLAY INVISIBLE (-3325 3775);
FORCEPROP 1 LAST HDL_TAP TRUE
J 2
(-3650 3600);
DISPLAY 0.872340 (-3650 3600);
DISPLAY INVISIBLE (-3650 3600);
FORCEPROP 1 LAST PATH I71
J 2
(-3323 3725);
DISPLAY 0.872340 (-3323 3725);
PAINT GREEN (-3323 3725);
DISPLAY INVISIBLE (-3323 3725);
FORCEADD TAP..1
R 2
(-3325 3875);
FORCEPROP 3 LASTPIN (-3275 3875) SIG_NAME M_D_CPU1_SA_CA<1>
J 0
(-3265 3885);
DISPLAY 0.659574 (-3265 3885);
PAINT MONO (-3265 3885);
DISPLAY INVISIBLE (-3265 3885);
FORCEPROP 1 LASTPIN (-3275 3875) BN 1
J 2
(-3263 3883);
DISPLAY 0.680851 (-3263 3883);
PAINT GREEN (-3263 3883);
FORCEPROP 2 LAST CDS_LIB standard
J 0
(-3325 3875);
DISPLAY INVISIBLE (-3325 3875);
FORCEPROP 1 LAST BODY_TYPE PLUMBING
J 2
(-3325 3925);
DISPLAY 0.872340 (-3325 3925);
PAINT GREEN (-3325 3925);
DISPLAY INVISIBLE (-3325 3925);
FORCEPROP 1 LAST HDL_TAP TRUE
J 2
(-3650 3750);
DISPLAY 0.872340 (-3650 3750);
DISPLAY INVISIBLE (-3650 3750);
FORCEPROP 1 LAST PATH I72
J 2
(-3323 3875);
DISPLAY 0.872340 (-3323 3875);
PAINT GREEN (-3323 3875);
DISPLAY INVISIBLE (-3323 3875);
FORCEADD TAP..1
R 2
(-3325 3825);
FORCEPROP 3 LASTPIN (-3275 3825) SIG_NAME M_D_CPU1_SA_CA<0>
J 0
(-3265 3835);
DISPLAY 0.659574 (-3265 3835);
PAINT MONO (-3265 3835);
DISPLAY INVISIBLE (-3265 3835);
FORCEPROP 1 LASTPIN (-3275 3825) BN 0
J 2
(-3263 3833);
DISPLAY 0.680851 (-3263 3833);
PAINT GREEN (-3263 3833);
FORCEPROP 2 LAST CDS_LIB standard
J 0
(-3325 3825);
DISPLAY INVISIBLE (-3325 3825);
FORCEPROP 1 LAST BODY_TYPE PLUMBING
J 2
(-3325 3875);
DISPLAY 0.872340 (-3325 3875);
PAINT GREEN (-3325 3875);
DISPLAY INVISIBLE (-3325 3875);
FORCEPROP 1 LAST HDL_TAP TRUE
J 2
(-3650 3700);
DISPLAY 0.872340 (-3650 3700);
DISPLAY INVISIBLE (-3650 3700);
FORCEPROP 1 LAST PATH I73
J 2
(-3323 3825);
DISPLAY 0.872340 (-3323 3825);
PAINT GREEN (-3323 3825);
DISPLAY INVISIBLE (-3323 3825);
FORCEADD TAP..1
R 2
(-3325 3675);
FORCEPROP 3 LASTPIN (-3275 3675) SIG_NAME M_D_CPU1_SB_CA<5>
J 0
(-3265 3685);
DISPLAY 0.659574 (-3265 3685);
PAINT MONO (-3265 3685);
DISPLAY INVISIBLE (-3265 3685);
FORCEPROP 1 LASTPIN (-3275 3675) BN 5
J 2
(-3263 3683);
DISPLAY 0.680851 (-3263 3683);
PAINT GREEN (-3263 3683);
FORCEPROP 2 LAST CDS_LIB standard
J 0
(-3325 3675);
DISPLAY INVISIBLE (-3325 3675);
FORCEPROP 1 LAST BODY_TYPE PLUMBING
J 2
(-3325 3725);
DISPLAY 0.872340 (-3325 3725);
PAINT GREEN (-3325 3725);
DISPLAY INVISIBLE (-3325 3725);
FORCEPROP 1 LAST HDL_TAP TRUE
J 2
(-3650 3550);
DISPLAY 0.872340 (-3650 3550);
DISPLAY INVISIBLE (-3650 3550);
FORCEPROP 1 LAST PATH I74
J 2
(-3323 3675);
DISPLAY 0.872340 (-3323 3675);
PAINT GREEN (-3323 3675);
DISPLAY INVISIBLE (-3323 3675);
FORCEADD TAP..1
R 2
(-3325 3925);
FORCEPROP 3 LASTPIN (-3275 3925) SIG_NAME M_D_CPU1_SA_CA<2>
J 0
(-3265 3935);
DISPLAY 0.659574 (-3265 3935);
PAINT MONO (-3265 3935);
DISPLAY INVISIBLE (-3265 3935);
FORCEPROP 1 LASTPIN (-3275 3925) BN 2
J 2
(-3263 3933);
DISPLAY 0.680851 (-3263 3933);
PAINT GREEN (-3263 3933);
FORCEPROP 2 LAST CDS_LIB standard
J 0
(-3325 3925);
DISPLAY INVISIBLE (-3325 3925);
FORCEPROP 1 LAST BODY_TYPE PLUMBING
J 2
(-3325 3975);
DISPLAY 0.872340 (-3325 3975);
PAINT GREEN (-3325 3975);
DISPLAY INVISIBLE (-3325 3975);
FORCEPROP 1 LAST HDL_TAP TRUE
J 2
(-3650 3800);
DISPLAY 0.872340 (-3650 3800);
DISPLAY INVISIBLE (-3650 3800);
FORCEPROP 1 LAST PATH I75
J 2
(-3323 3925);
DISPLAY 0.872340 (-3323 3925);
PAINT GREEN (-3323 3925);
DISPLAY INVISIBLE (-3323 3925);
FORCEADD TAP..1
R 2
(-3325 3975);
FORCEPROP 3 LASTPIN (-3275 3975) SIG_NAME M_D_CPU1_SA_CA<3>
J 0
(-3265 3985);
DISPLAY 0.659574 (-3265 3985);
PAINT MONO (-3265 3985);
DISPLAY INVISIBLE (-3265 3985);
FORCEPROP 1 LASTPIN (-3275 3975) BN 3
J 2
(-3263 3983);
DISPLAY 0.680851 (-3263 3983);
PAINT GREEN (-3263 3983);
FORCEPROP 2 LAST CDS_LIB standard
J 0
(-3325 3975);
DISPLAY INVISIBLE (-3325 3975);
FORCEPROP 1 LAST BODY_TYPE PLUMBING
J 2
(-3325 4025);
DISPLAY 0.872340 (-3325 4025);
PAINT GREEN (-3325 4025);
DISPLAY INVISIBLE (-3325 4025);
FORCEPROP 1 LAST HDL_TAP TRUE
J 2
(-3650 3850);
DISPLAY 0.872340 (-3650 3850);
DISPLAY INVISIBLE (-3650 3850);
FORCEPROP 1 LAST PATH I76
J 2
(-3323 3975);
DISPLAY 0.872340 (-3323 3975);
PAINT GREEN (-3323 3975);
DISPLAY INVISIBLE (-3323 3975);
FORCEADD TAP..1
R 2
(-3325 4125);
FORCEPROP 3 LASTPIN (-3275 4125) SIG_NAME M_D_CPU1_SA_CA<6>
J 0
(-3265 4135);
DISPLAY 0.659574 (-3265 4135);
PAINT MONO (-3265 4135);
DISPLAY INVISIBLE (-3265 4135);
FORCEPROP 1 LASTPIN (-3275 4125) BN 6
J 2
(-3263 4133);
DISPLAY 0.680851 (-3263 4133);
PAINT GREEN (-3263 4133);
FORCEPROP 2 LAST CDS_LIB standard
J 0
(-3325 4125);
DISPLAY INVISIBLE (-3325 4125);
FORCEPROP 1 LAST BODY_TYPE PLUMBING
J 2
(-3325 4175);
DISPLAY 0.872340 (-3325 4175);
PAINT GREEN (-3325 4175);
DISPLAY INVISIBLE (-3325 4175);
FORCEPROP 1 LAST HDL_TAP TRUE
J 2
(-3650 4000);
DISPLAY 0.872340 (-3650 4000);
DISPLAY INVISIBLE (-3650 4000);
FORCEPROP 1 LAST PATH I77
J 2
(-3323 4125);
DISPLAY 0.872340 (-3323 4125);
PAINT GREEN (-3323 4125);
DISPLAY INVISIBLE (-3323 4125);
FORCEADD TAP..1
R 2
(-3325 4075);
FORCEPROP 3 LASTPIN (-3275 4075) SIG_NAME M_D_CPU1_SA_CA<5>
J 0
(-3265 4085);
DISPLAY 0.659574 (-3265 4085);
PAINT MONO (-3265 4085);
DISPLAY INVISIBLE (-3265 4085);
FORCEPROP 1 LASTPIN (-3275 4075) BN 5
J 2
(-3263 4083);
DISPLAY 0.680851 (-3263 4083);
PAINT GREEN (-3263 4083);
FORCEPROP 2 LAST CDS_LIB standard
J 0
(-3325 4075);
DISPLAY INVISIBLE (-3325 4075);
FORCEPROP 1 LAST BODY_TYPE PLUMBING
J 2
(-3325 4125);
DISPLAY 0.872340 (-3325 4125);
PAINT GREEN (-3325 4125);
DISPLAY INVISIBLE (-3325 4125);
FORCEPROP 1 LAST HDL_TAP TRUE
J 2
(-3650 3950);
DISPLAY 0.872340 (-3650 3950);
DISPLAY INVISIBLE (-3650 3950);
FORCEPROP 1 LAST PATH I78
J 2
(-3323 4075);
DISPLAY 0.872340 (-3323 4075);
PAINT GREEN (-3323 4075);
DISPLAY INVISIBLE (-3323 4075);
FORCEADD TAP..1
R 2
(-3325 4025);
FORCEPROP 3 LASTPIN (-3275 4025) SIG_NAME M_D_CPU1_SA_CA<4>
J 0
(-3265 4035);
DISPLAY 0.659574 (-3265 4035);
PAINT MONO (-3265 4035);
DISPLAY INVISIBLE (-3265 4035);
FORCEPROP 1 LASTPIN (-3275 4025) BN 4
J 2
(-3263 4033);
DISPLAY 0.680851 (-3263 4033);
PAINT GREEN (-3263 4033);
FORCEPROP 2 LAST CDS_LIB standard
J 0
(-3325 4025);
DISPLAY INVISIBLE (-3325 4025);
FORCEPROP 1 LAST BODY_TYPE PLUMBING
J 2
(-3325 4075);
DISPLAY 0.872340 (-3325 4075);
PAINT GREEN (-3325 4075);
DISPLAY INVISIBLE (-3325 4075);
FORCEPROP 1 LAST HDL_TAP TRUE
J 2
(-3650 3900);
DISPLAY 0.872340 (-3650 3900);
DISPLAY INVISIBLE (-3650 3900);
FORCEPROP 1 LAST PATH I79
J 2
(-3323 4025);
DISPLAY 0.872340 (-3323 4025);
PAINT GREEN (-3323 4025);
DISPLAY INVISIBLE (-3323 4025);
FORCEADD TAP..1
(-1675 2225);
FORCEPROP 3 LASTPIN (-1725 2225) SIG_NAME M_D_CPU1_SB_DQ<26>
J 0
(-1715 2235);
DISPLAY 0.659574 (-1715 2235);
PAINT MONO (-1715 2235);
DISPLAY INVISIBLE (-1715 2235);
FORCEPROP 1 LASTPIN (-1725 2225) BN 26
J 0
(-1737 2233);
DISPLAY 0.680851 (-1737 2233);
PAINT GREEN (-1737 2233);
FORCEPROP 2 LAST CDS_LIB standard
J 0
(-1675 2225);
DISPLAY INVISIBLE (-1675 2225);
FORCEPROP 1 LAST BODY_TYPE PLUMBING
J 0
(-1675 2275);
DISPLAY 0.872340 (-1675 2275);
PAINT GREEN (-1675 2275);
DISPLAY INVISIBLE (-1675 2275);
FORCEPROP 1 LAST HDL_TAP TRUE
J 0
(-1350 2100);
DISPLAY 0.872340 (-1350 2100);
DISPLAY INVISIBLE (-1350 2100);
FORCEPROP 1 LAST PATH I80
J 0
(-1677 2225);
DISPLAY 0.872340 (-1677 2225);
PAINT GREEN (-1677 2225);
DISPLAY INVISIBLE (-1677 2225);
FORCEADD TAP..1
(-1675 2175);
FORCEPROP 3 LASTPIN (-1725 2175) SIG_NAME M_D_CPU1_SB_DQ<25>
J 0
(-1715 2185);
DISPLAY 0.659574 (-1715 2185);
PAINT MONO (-1715 2185);
DISPLAY INVISIBLE (-1715 2185);
FORCEPROP 1 LASTPIN (-1725 2175) BN 25
J 0
(-1737 2183);
DISPLAY 0.680851 (-1737 2183);
PAINT GREEN (-1737 2183);
FORCEPROP 2 LAST CDS_LIB standard
J 0
(-1675 2175);
DISPLAY INVISIBLE (-1675 2175);
FORCEPROP 1 LAST BODY_TYPE PLUMBING
J 0
(-1675 2225);
DISPLAY 0.872340 (-1675 2225);
PAINT GREEN (-1675 2225);
DISPLAY INVISIBLE (-1675 2225);
FORCEPROP 1 LAST HDL_TAP TRUE
J 0
(-1350 2050);
DISPLAY 0.872340 (-1350 2050);
DISPLAY INVISIBLE (-1350 2050);
FORCEPROP 1 LAST PATH I81
J 0
(-1677 2175);
DISPLAY 0.872340 (-1677 2175);
PAINT GREEN (-1677 2175);
DISPLAY INVISIBLE (-1677 2175);
FORCEADD TAP..1
(-1675 2125);
FORCEPROP 3 LASTPIN (-1725 2125) SIG_NAME M_D_CPU1_SB_DQ<24>
J 0
(-1715 2135);
DISPLAY 0.659574 (-1715 2135);
PAINT MONO (-1715 2135);
DISPLAY INVISIBLE (-1715 2135);
FORCEPROP 1 LASTPIN (-1725 2125) BN 24
J 0
(-1737 2133);
DISPLAY 0.680851 (-1737 2133);
PAINT GREEN (-1737 2133);
FORCEPROP 2 LAST CDS_LIB standard
J 0
(-1675 2125);
DISPLAY INVISIBLE (-1675 2125);
FORCEPROP 1 LAST BODY_TYPE PLUMBING
J 0
(-1675 2175);
DISPLAY 0.872340 (-1675 2175);
PAINT GREEN (-1675 2175);
DISPLAY INVISIBLE (-1675 2175);
FORCEPROP 1 LAST HDL_TAP TRUE
J 0
(-1350 2000);
DISPLAY 0.872340 (-1350 2000);
DISPLAY INVISIBLE (-1350 2000);
FORCEPROP 1 LAST PATH I82
J 0
(-1677 2125);
DISPLAY 0.872340 (-1677 2125);
PAINT GREEN (-1677 2125);
DISPLAY INVISIBLE (-1677 2125);
FORCEADD TAP..1
(-1675 2325);
FORCEPROP 3 LASTPIN (-1725 2325) SIG_NAME M_D_CPU1_SB_DQ<28>
J 0
(-1715 2335);
DISPLAY 0.659574 (-1715 2335);
PAINT MONO (-1715 2335);
DISPLAY INVISIBLE (-1715 2335);
FORCEPROP 1 LASTPIN (-1725 2325) BN 28
J 0
(-1737 2333);
DISPLAY 0.680851 (-1737 2333);
PAINT GREEN (-1737 2333);
FORCEPROP 2 LAST CDS_LIB standard
J 0
(-1675 2325);
DISPLAY INVISIBLE (-1675 2325);
FORCEPROP 1 LAST BODY_TYPE PLUMBING
J 0
(-1675 2375);
DISPLAY 0.872340 (-1675 2375);
PAINT GREEN (-1675 2375);
DISPLAY INVISIBLE (-1675 2375);
FORCEPROP 1 LAST HDL_TAP TRUE
J 0
(-1350 2200);
DISPLAY 0.872340 (-1350 2200);
DISPLAY INVISIBLE (-1350 2200);
FORCEPROP 1 LAST PATH I83
J 0
(-1677 2325);
DISPLAY 0.872340 (-1677 2325);
PAINT GREEN (-1677 2325);
DISPLAY INVISIBLE (-1677 2325);
FORCEADD TAP..1
(-1675 2375);
FORCEPROP 3 LASTPIN (-1725 2375) SIG_NAME M_D_CPU1_SB_DQ<29>
J 0
(-1715 2385);
DISPLAY 0.659574 (-1715 2385);
PAINT MONO (-1715 2385);
DISPLAY INVISIBLE (-1715 2385);
FORCEPROP 1 LASTPIN (-1725 2375) BN 29
J 0
(-1737 2383);
DISPLAY 0.680851 (-1737 2383);
PAINT GREEN (-1737 2383);
FORCEPROP 2 LAST CDS_LIB standard
J 0
(-1675 2375);
DISPLAY INVISIBLE (-1675 2375);
FORCEPROP 1 LAST BODY_TYPE PLUMBING
J 0
(-1675 2425);
DISPLAY 0.872340 (-1675 2425);
PAINT GREEN (-1675 2425);
DISPLAY INVISIBLE (-1675 2425);
FORCEPROP 1 LAST HDL_TAP TRUE
J 0
(-1350 2250);
DISPLAY 0.872340 (-1350 2250);
DISPLAY INVISIBLE (-1350 2250);
FORCEPROP 1 LAST PATH I84
J 0
(-1677 2375);
DISPLAY 0.872340 (-1677 2375);
PAINT GREEN (-1677 2375);
DISPLAY INVISIBLE (-1677 2375);
FORCEADD TAP..1
(-1675 2275);
FORCEPROP 3 LASTPIN (-1725 2275) SIG_NAME M_D_CPU1_SB_DQ<27>
J 0
(-1715 2285);
DISPLAY 0.659574 (-1715 2285);
PAINT MONO (-1715 2285);
DISPLAY INVISIBLE (-1715 2285);
FORCEPROP 1 LASTPIN (-1725 2275) BN 27
J 0
(-1737 2283);
DISPLAY 0.680851 (-1737 2283);
PAINT GREEN (-1737 2283);
FORCEPROP 2 LAST CDS_LIB standard
J 0
(-1675 2275);
DISPLAY INVISIBLE (-1675 2275);
FORCEPROP 1 LAST BODY_TYPE PLUMBING
J 0
(-1675 2325);
DISPLAY 0.872340 (-1675 2325);
PAINT GREEN (-1675 2325);
DISPLAY INVISIBLE (-1675 2325);
FORCEPROP 1 LAST HDL_TAP TRUE
J 0
(-1350 2150);
DISPLAY 0.872340 (-1350 2150);
DISPLAY INVISIBLE (-1350 2150);
FORCEPROP 1 LAST PATH I85
J 0
(-1677 2275);
DISPLAY 0.872340 (-1677 2275);
PAINT GREEN (-1677 2275);
DISPLAY INVISIBLE (-1677 2275);
FORCEADD TAP..1
(-1675 2625);
FORCEPROP 3 LASTPIN (-1725 2625) SIG_NAME M_D_CPU1_SA_DQ<1>
J 0
(-1715 2635);
DISPLAY 0.659574 (-1715 2635);
PAINT MONO (-1715 2635);
DISPLAY INVISIBLE (-1715 2635);
FORCEPROP 1 LASTPIN (-1725 2625) BN 1
J 0
(-1737 2633);
DISPLAY 0.680851 (-1737 2633);
PAINT GREEN (-1737 2633);
FORCEPROP 2 LAST CDS_LIB standard
J 0
(-1675 2625);
PAINT MONO (-1675 2625);
DISPLAY INVISIBLE (-1675 2625);
FORCEPROP 1 LAST BODY_TYPE PLUMBING
J 0
(-1675 2675);
DISPLAY 0.872340 (-1675 2675);
PAINT GREEN (-1675 2675);
DISPLAY INVISIBLE (-1675 2675);
FORCEPROP 1 LAST HDL_TAP TRUE
J 0
(-1350 2500);
DISPLAY 0.872340 (-1350 2500);
DISPLAY INVISIBLE (-1350 2500);
FORCEPROP 1 LAST PATH I86
J 0
(-1677 2625);
DISPLAY 0.872340 (-1677 2625);
PAINT GREEN (-1677 2625);
DISPLAY INVISIBLE (-1677 2625);
FORCEADD TAP..1
(-1675 2575);
FORCEPROP 3 LASTPIN (-1725 2575) SIG_NAME M_D_CPU1_SA_DQ<0>
J 0
(-1715 2585);
DISPLAY 0.659574 (-1715 2585);
PAINT MONO (-1715 2585);
DISPLAY INVISIBLE (-1715 2585);
FORCEPROP 1 LASTPIN (-1725 2575) BN 0
J 0
(-1737 2583);
DISPLAY 0.680851 (-1737 2583);
PAINT GREEN (-1737 2583);
FORCEPROP 2 LAST CDS_LIB standard
J 0
(-1675 2575);
PAINT MONO (-1675 2575);
DISPLAY INVISIBLE (-1675 2575);
FORCEPROP 1 LAST BODY_TYPE PLUMBING
J 0
(-1675 2625);
DISPLAY 0.872340 (-1675 2625);
PAINT GREEN (-1675 2625);
DISPLAY INVISIBLE (-1675 2625);
FORCEPROP 1 LAST HDL_TAP TRUE
J 0
(-1350 2450);
DISPLAY 0.872340 (-1350 2450);
DISPLAY INVISIBLE (-1350 2450);
FORCEPROP 1 LAST PATH I87
J 0
(-1677 2575);
DISPLAY 0.872340 (-1677 2575);
PAINT GREEN (-1677 2575);
DISPLAY INVISIBLE (-1677 2575);
FORCEADD TAP..1
(-1675 2425);
FORCEPROP 3 LASTPIN (-1725 2425) SIG_NAME M_D_CPU1_SB_DQ<30>
J 0
(-1715 2435);
DISPLAY 0.659574 (-1715 2435);
PAINT MONO (-1715 2435);
DISPLAY INVISIBLE (-1715 2435);
FORCEPROP 1 LASTPIN (-1725 2425) BN 30
J 0
(-1737 2433);
DISPLAY 0.680851 (-1737 2433);
PAINT GREEN (-1737 2433);
FORCEPROP 2 LAST CDS_LIB standard
J 0
(-1675 2425);
DISPLAY INVISIBLE (-1675 2425);
FORCEPROP 1 LAST BODY_TYPE PLUMBING
J 0
(-1675 2475);
DISPLAY 0.872340 (-1675 2475);
PAINT GREEN (-1675 2475);
DISPLAY INVISIBLE (-1675 2475);
FORCEPROP 1 LAST HDL_TAP TRUE
J 0
(-1350 2300);
DISPLAY 0.872340 (-1350 2300);
DISPLAY INVISIBLE (-1350 2300);
FORCEPROP 1 LAST PATH I88
J 0
(-1677 2425);
DISPLAY 0.872340 (-1677 2425);
PAINT GREEN (-1677 2425);
DISPLAY INVISIBLE (-1677 2425);
FORCEADD TAP..1
(-1675 2475);
FORCEPROP 3 LASTPIN (-1725 2475) SIG_NAME M_D_CPU1_SB_DQ<31>
J 0
(-1715 2485);
DISPLAY 0.659574 (-1715 2485);
PAINT MONO (-1715 2485);
DISPLAY INVISIBLE (-1715 2485);
FORCEPROP 1 LASTPIN (-1725 2475) BN 31
J 0
(-1737 2483);
DISPLAY 0.680851 (-1737 2483);
PAINT GREEN (-1737 2483);
FORCEPROP 2 LAST CDS_LIB standard
J 0
(-1675 2475);
DISPLAY INVISIBLE (-1675 2475);
FORCEPROP 1 LAST BODY_TYPE PLUMBING
J 0
(-1675 2525);
DISPLAY 0.872340 (-1675 2525);
PAINT GREEN (-1675 2525);
DISPLAY INVISIBLE (-1675 2525);
FORCEPROP 1 LAST HDL_TAP TRUE
J 0
(-1350 2350);
DISPLAY 0.872340 (-1350 2350);
DISPLAY INVISIBLE (-1350 2350);
FORCEPROP 1 LAST PATH I89
J 0
(-1677 2475);
DISPLAY 0.872340 (-1677 2475);
PAINT GREEN (-1677 2475);
DISPLAY INVISIBLE (-1677 2475);
FORCEADD OFFPAGE..1
(-4175 1625);
FORCEPROP 2 LAST $XR0 104 
J 0
(-4667 1625);
DISPLAY 0.638298 (-4667 1625);
PAINT MONO (-4667 1625);
FORCEPROP 2 LAST CDS_LIB standard
J 0
(-4175 1625);
PAINT MONO (-4175 1625);
DISPLAY INVISIBLE (-4175 1625);
FORCEPROP 1 LAST OFFPAGE TRUE
J 0
(-3850 1500);
DISPLAY 0.872340 (-3850 1500);
DISPLAY INVISIBLE (-3850 1500);
FORCEPROP 1 LAST COMMENT_BODY TRUE
J 0
(-4050 1525);
DISPLAY 0.872340 (-4050 1525);
PAINT GREEN (-4050 1525);
DISPLAY INVISIBLE (-4050 1525);
FORCEPROP 2 LAST PATH I9
J 0
(-4125 1700);
DISPLAY 1.021277 (-4125 1700);
DISPLAY INVISIBLE (-4125 1700);
FORCEADD TAP..1
(-1675 2725);
FORCEPROP 3 LASTPIN (-1725 2725) SIG_NAME M_D_CPU1_SA_DQ<3>
J 0
(-1715 2735);
DISPLAY 0.659574 (-1715 2735);
PAINT MONO (-1715 2735);
DISPLAY INVISIBLE (-1715 2735);
FORCEPROP 1 LASTPIN (-1725 2725) BN 3
J 0
(-1737 2733);
DISPLAY 0.680851 (-1737 2733);
PAINT GREEN (-1737 2733);
FORCEPROP 2 LAST CDS_LIB standard
J 0
(-1675 2725);
PAINT MONO (-1675 2725);
DISPLAY INVISIBLE (-1675 2725);
FORCEPROP 1 LAST BODY_TYPE PLUMBING
J 0
(-1675 2775);
DISPLAY 0.872340 (-1675 2775);
PAINT GREEN (-1675 2775);
DISPLAY INVISIBLE (-1675 2775);
FORCEPROP 1 LAST HDL_TAP TRUE
J 0
(-1350 2600);
DISPLAY 0.872340 (-1350 2600);
DISPLAY INVISIBLE (-1350 2600);
FORCEPROP 1 LAST PATH I90
J 0
(-1677 2725);
DISPLAY 0.872340 (-1677 2725);
PAINT GREEN (-1677 2725);
DISPLAY INVISIBLE (-1677 2725);
FORCEADD TAP..1
(-1675 2675);
FORCEPROP 3 LASTPIN (-1725 2675) SIG_NAME M_D_CPU1_SA_DQ<2>
J 0
(-1715 2685);
DISPLAY 0.659574 (-1715 2685);
PAINT MONO (-1715 2685);
DISPLAY INVISIBLE (-1715 2685);
FORCEPROP 1 LASTPIN (-1725 2675) BN 2
J 0
(-1737 2683);
DISPLAY 0.680851 (-1737 2683);
PAINT GREEN (-1737 2683);
FORCEPROP 2 LAST CDS_LIB standard
J 0
(-1675 2675);
PAINT MONO (-1675 2675);
DISPLAY INVISIBLE (-1675 2675);
FORCEPROP 1 LAST BODY_TYPE PLUMBING
J 0
(-1675 2725);
DISPLAY 0.872340 (-1675 2725);
PAINT GREEN (-1675 2725);
DISPLAY INVISIBLE (-1675 2725);
FORCEPROP 1 LAST HDL_TAP TRUE
J 0
(-1350 2550);
DISPLAY 0.872340 (-1350 2550);
DISPLAY INVISIBLE (-1350 2550);
FORCEPROP 1 LAST PATH I91
J 0
(-1677 2675);
DISPLAY 0.872340 (-1677 2675);
PAINT GREEN (-1677 2675);
DISPLAY INVISIBLE (-1677 2675);
FORCEADD TAP..1
(-1675 2825);
FORCEPROP 3 LASTPIN (-1725 2825) SIG_NAME M_D_CPU1_SA_DQ<5>
J 0
(-1715 2835);
DISPLAY 0.659574 (-1715 2835);
PAINT MONO (-1715 2835);
DISPLAY INVISIBLE (-1715 2835);
FORCEPROP 1 LASTPIN (-1725 2825) BN 5
J 0
(-1737 2833);
DISPLAY 0.680851 (-1737 2833);
PAINT GREEN (-1737 2833);
FORCEPROP 2 LAST CDS_LIB standard
J 0
(-1675 2825);
PAINT MONO (-1675 2825);
DISPLAY INVISIBLE (-1675 2825);
FORCEPROP 1 LAST BODY_TYPE PLUMBING
J 0
(-1675 2875);
DISPLAY 0.872340 (-1675 2875);
PAINT GREEN (-1675 2875);
DISPLAY INVISIBLE (-1675 2875);
FORCEPROP 1 LAST HDL_TAP TRUE
J 0
(-1350 2700);
DISPLAY 0.872340 (-1350 2700);
DISPLAY INVISIBLE (-1350 2700);
FORCEPROP 1 LAST PATH I92
J 0
(-1677 2825);
DISPLAY 0.872340 (-1677 2825);
PAINT GREEN (-1677 2825);
DISPLAY INVISIBLE (-1677 2825);
FORCEADD TAP..1
(-1675 2875);
FORCEPROP 3 LASTPIN (-1725 2875) SIG_NAME M_D_CPU1_SA_DQ<6>
J 0
(-1715 2885);
DISPLAY 0.659574 (-1715 2885);
PAINT MONO (-1715 2885);
DISPLAY INVISIBLE (-1715 2885);
FORCEPROP 1 LASTPIN (-1725 2875) BN 6
J 0
(-1737 2883);
DISPLAY 0.680851 (-1737 2883);
PAINT GREEN (-1737 2883);
FORCEPROP 2 LAST CDS_LIB standard
J 0
(-1675 2875);
PAINT MONO (-1675 2875);
DISPLAY INVISIBLE (-1675 2875);
FORCEPROP 1 LAST BODY_TYPE PLUMBING
J 0
(-1675 2925);
DISPLAY 0.872340 (-1675 2925);
PAINT GREEN (-1675 2925);
DISPLAY INVISIBLE (-1675 2925);
FORCEPROP 1 LAST HDL_TAP TRUE
J 0
(-1350 2750);
DISPLAY 0.872340 (-1350 2750);
DISPLAY INVISIBLE (-1350 2750);
FORCEPROP 1 LAST PATH I93
J 0
(-1677 2875);
DISPLAY 0.872340 (-1677 2875);
PAINT GREEN (-1677 2875);
DISPLAY INVISIBLE (-1677 2875);
FORCEADD TAP..1
(-1675 2775);
FORCEPROP 3 LASTPIN (-1725 2775) SIG_NAME M_D_CPU1_SA_DQ<4>
J 0
(-1715 2785);
DISPLAY 0.659574 (-1715 2785);
PAINT MONO (-1715 2785);
DISPLAY INVISIBLE (-1715 2785);
FORCEPROP 1 LASTPIN (-1725 2775) BN 4
J 0
(-1737 2783);
DISPLAY 0.680851 (-1737 2783);
PAINT GREEN (-1737 2783);
FORCEPROP 2 LAST CDS_LIB standard
J 0
(-1675 2775);
PAINT MONO (-1675 2775);
DISPLAY INVISIBLE (-1675 2775);
FORCEPROP 1 LAST BODY_TYPE PLUMBING
J 0
(-1675 2825);
DISPLAY 0.872340 (-1675 2825);
PAINT GREEN (-1675 2825);
DISPLAY INVISIBLE (-1675 2825);
FORCEPROP 1 LAST HDL_TAP TRUE
J 0
(-1350 2650);
DISPLAY 0.872340 (-1350 2650);
DISPLAY INVISIBLE (-1350 2650);
FORCEPROP 1 LAST PATH I94
J 0
(-1677 2775);
DISPLAY 0.872340 (-1677 2775);
PAINT GREEN (-1677 2775);
DISPLAY INVISIBLE (-1677 2775);
FORCEADD TAP..1
(-1675 2925);
FORCEPROP 3 LASTPIN (-1725 2925) SIG_NAME M_D_CPU1_SA_DQ<7>
J 0
(-1715 2935);
DISPLAY 0.659574 (-1715 2935);
PAINT MONO (-1715 2935);
DISPLAY INVISIBLE (-1715 2935);
FORCEPROP 1 LASTPIN (-1725 2925) BN 7
J 0
(-1737 2933);
DISPLAY 0.680851 (-1737 2933);
PAINT GREEN (-1737 2933);
FORCEPROP 2 LAST CDS_LIB standard
J 0
(-1675 2925);
PAINT MONO (-1675 2925);
DISPLAY INVISIBLE (-1675 2925);
FORCEPROP 1 LAST BODY_TYPE PLUMBING
J 0
(-1675 2975);
DISPLAY 0.872340 (-1675 2975);
PAINT GREEN (-1675 2975);
DISPLAY INVISIBLE (-1675 2975);
FORCEPROP 1 LAST HDL_TAP TRUE
J 0
(-1350 2800);
DISPLAY 0.872340 (-1350 2800);
DISPLAY INVISIBLE (-1350 2800);
FORCEPROP 1 LAST PATH I95
J 0
(-1677 2925);
DISPLAY 0.872340 (-1677 2925);
PAINT GREEN (-1677 2925);
DISPLAY INVISIBLE (-1677 2925);
FORCEADD TAP..1
(-1675 2975);
FORCEPROP 3 LASTPIN (-1725 2975) SIG_NAME M_D_CPU1_SA_DQ<8>
J 0
(-1715 2985);
DISPLAY 0.659574 (-1715 2985);
PAINT MONO (-1715 2985);
DISPLAY INVISIBLE (-1715 2985);
FORCEPROP 1 LASTPIN (-1725 2975) BN 8
J 0
(-1737 2983);
DISPLAY 0.680851 (-1737 2983);
PAINT GREEN (-1737 2983);
FORCEPROP 2 LAST CDS_LIB standard
J 0
(-1675 2975);
PAINT MONO (-1675 2975);
DISPLAY INVISIBLE (-1675 2975);
FORCEPROP 1 LAST BODY_TYPE PLUMBING
J 0
(-1675 3025);
DISPLAY 0.872340 (-1675 3025);
PAINT GREEN (-1675 3025);
DISPLAY INVISIBLE (-1675 3025);
FORCEPROP 1 LAST HDL_TAP TRUE
J 0
(-1350 2850);
DISPLAY 0.872340 (-1350 2850);
DISPLAY INVISIBLE (-1350 2850);
FORCEPROP 1 LAST PATH I96
J 0
(-1677 2975);
DISPLAY 0.872340 (-1677 2975);
PAINT GREEN (-1677 2975);
DISPLAY INVISIBLE (-1677 2975);
FORCEADD TAP..1
(-1675 3025);
FORCEPROP 3 LASTPIN (-1725 3025) SIG_NAME M_D_CPU1_SA_DQ<9>
J 0
(-1715 3035);
DISPLAY 0.659574 (-1715 3035);
PAINT MONO (-1715 3035);
DISPLAY INVISIBLE (-1715 3035);
FORCEPROP 1 LASTPIN (-1725 3025) BN 9
J 0
(-1737 3033);
DISPLAY 0.680851 (-1737 3033);
PAINT GREEN (-1737 3033);
FORCEPROP 2 LAST CDS_LIB standard
J 0
(-1675 3025);
PAINT MONO (-1675 3025);
DISPLAY INVISIBLE (-1675 3025);
FORCEPROP 1 LAST BODY_TYPE PLUMBING
J 0
(-1675 3075);
DISPLAY 0.872340 (-1675 3075);
PAINT GREEN (-1675 3075);
DISPLAY INVISIBLE (-1675 3075);
FORCEPROP 1 LAST HDL_TAP TRUE
J 0
(-1350 2900);
DISPLAY 0.872340 (-1350 2900);
DISPLAY INVISIBLE (-1350 2900);
FORCEPROP 1 LAST PATH I97
J 0
(-1677 3025);
DISPLAY 0.872340 (-1677 3025);
PAINT GREEN (-1677 3025);
DISPLAY INVISIBLE (-1677 3025);
FORCEADD TAP..1
(-1675 3075);
FORCEPROP 3 LASTPIN (-1725 3075) SIG_NAME M_D_CPU1_SA_DQ<10>
J 0
(-1715 3085);
DISPLAY 0.659574 (-1715 3085);
PAINT MONO (-1715 3085);
DISPLAY INVISIBLE (-1715 3085);
FORCEPROP 1 LASTPIN (-1725 3075) BN 10
J 0
(-1737 3083);
DISPLAY 0.680851 (-1737 3083);
PAINT GREEN (-1737 3083);
FORCEPROP 2 LAST CDS_LIB standard
J 0
(-1675 3075);
PAINT MONO (-1675 3075);
DISPLAY INVISIBLE (-1675 3075);
FORCEPROP 1 LAST BODY_TYPE PLUMBING
J 0
(-1675 3125);
DISPLAY 0.872340 (-1675 3125);
PAINT GREEN (-1675 3125);
DISPLAY INVISIBLE (-1675 3125);
FORCEPROP 1 LAST HDL_TAP TRUE
J 0
(-1350 2950);
DISPLAY 0.872340 (-1350 2950);
DISPLAY INVISIBLE (-1350 2950);
FORCEPROP 1 LAST PATH I98
J 0
(-1677 3075);
DISPLAY 0.872340 (-1677 3075);
PAINT GREEN (-1677 3075);
DISPLAY INVISIBLE (-1677 3075);
FORCEADD TAP..1
(-1675 3125);
FORCEPROP 3 LASTPIN (-1725 3125) SIG_NAME M_D_CPU1_SA_DQ<11>
J 0
(-1715 3135);
DISPLAY 0.659574 (-1715 3135);
PAINT MONO (-1715 3135);
DISPLAY INVISIBLE (-1715 3135);
FORCEPROP 1 LASTPIN (-1725 3125) BN 11
J 0
(-1737 3133);
DISPLAY 0.680851 (-1737 3133);
PAINT GREEN (-1737 3133);
FORCEPROP 2 LAST CDS_LIB standard
J 0
(-1675 3125);
PAINT MONO (-1675 3125);
DISPLAY INVISIBLE (-1675 3125);
FORCEPROP 1 LAST BODY_TYPE PLUMBING
J 0
(-1675 3175);
DISPLAY 0.872340 (-1675 3175);
PAINT GREEN (-1675 3175);
DISPLAY INVISIBLE (-1675 3175);
FORCEPROP 1 LAST HDL_TAP TRUE
J 0
(-1350 3000);
DISPLAY 0.872340 (-1350 3000);
DISPLAY INVISIBLE (-1350 3000);
FORCEPROP 1 LAST PATH I99
J 0
(-1677 3125);
DISPLAY 0.872340 (-1677 3125);
PAINT GREEN (-1677 3125);
DISPLAY INVISIBLE (-1677 3125);
FORCEADD CAD_NOTE..1
(175 -325);
FORCEPROP 0 LAST S1 PLACE THE BYPASS CAPS CLOSE TO DIMM
J 0
(50 -450);
DISPLAY 1.021277 (50 -450);
PAINT WHITE (50 -450);
FORCEPROP 2 LAST CDS_LIB logical_power
J 0
(175 -325);
PAINT MONO (175 -325);
DISPLAY INVISIBLE (175 -325);
FORCEPROP 1 LAST COMMENT_BODY TRUE
J 0
(200 -225);
DISPLAY 0.978723 (200 -225);
DISPLAY INVISIBLE (200 -225);
FORCEADD QUANTA_TITLE_BLOCK_C..1
(4650 -1625);
FORCEPROP 0 LAST CDS_CON_LAST_MODIFIED Fri Aug 25 14:01:24 2023
J 0
(2765 -1610);
PAINT MONO (2765 -1610);
DISPLAY INVISIBLE (2765 -1610);
FORCEPROP 1 LAST CUSTOM_TXT_CDS <CON_LAST_MODIFIED>
J 0
(2765 -1610);
DISPLAY 0.978723 (2765 -1610);
FORCEPROP 2 LAST CUSTOM_TXT_CDS <XR_PAGE_TITLE>
J 0
(-3240 3625);
DISPLAY 0.638298 (-3240 3625);
PAINT PINK (-3240 3625);
DISPLAY INVISIBLE (-3240 3625);
FORCEPROP 2 LAST CUSTOM_TXT_CDS <Q_NUMBER>
J 0
(3247 -1522);
DISPLAY 1.212766 (3247 -1522);
FORCEPROP 1 LAST CUSTOM_TXT_CDS <NAME_2>
J 0
(1475 -1575);
FORCEPROP 1 LAST CUSTOM_TXT_CDS <NAME_1>
J 0
(1475 -1450);
FORCEPROP 1 LAST CUSTOM_TXT_CDS <Q_PROJ>
J 0
(2268 -1523);
DISPLAY 1.212766 (2268 -1523);
FORCEPROP 1 LAST CUSTOM_TXT_CDS <Q_REV>
J 0
(4466 -1522);
DISPLAY 1.212766 (4466 -1522);
FORCEPROP 1 LAST CUSTOM_TXT_CDS <CON_PAGE_NUM> OF <CON_TOTAL_PAGES>
J 0
(4204 -1607);
DISPLAY 0.978723 (4204 -1607);
FORCEPROP 1 LAST Q_TITLE DDR5 - CPU1 CHD DIMM1(YELLOW)
J 0
(-4716 -1599);
DISPLAY 2.446809 (-4716 -1599);
PAINT GREEN (-4716 -1599);
FORCEPROP 1 LAST Q_DEPT 
J 1
(887 -1576);
DISPLAY 1.957447 (887 -1576);
PAINT GREEN (887 -1576);
FORCEPROP 2 LAST CDS_XR_PAGE_TITLE CR-104 : @S9S_MB_2U_LIB.S9S_MB_2U(SCH_1):PAGE104
J 0
(-3240 3625);
DISPLAY 0.638298 (-3240 3625);
PAINT PINK (-3240 3625);
DISPLAY INVISIBLE (-3240 3625);
FORCEPROP 1 LAST COMMENT_BODY TRUE
J 0
(4662 -1638);
DISPLAY 0.978723 (4662 -1638);
PAINT GREEN (4662 -1638);
DISPLAY INVISIBLE (4662 -1638);
FORCEPROP 2 LAST CDS_LIB pure_quanta
J 0
(4650 -1625);
PAINT MONO (4650 -1625);
DISPLAY INVISIBLE (4650 -1625);
FORCEPROP 1 LAST CDS_LMAN_SYM_OUTLINE -9475,6775,100,-125
J 0
(4650 -1625);
DISPLAY 0.468085 (4650 -1625);
PAINT GREEN (4650 -1625);
DISPLAY INVISIBLE (4650 -1625);
FORCEPROP 2 LAST PAGE_BORDER TRUE
J 0
(-3240 3625);
DISPLAY 0.638298 (-3240 3625);
PAINT PINK (-3240 3625);
DISPLAY INVISIBLE (-3240 3625);
WIRE 17 -1 (-1625 4100)(-1625 4150);
WIRE 17 -1 (-1625 4050)(-1625 4100);
WIRE 17 -1 (-1625 4150)(-900 4150);
FORCEPROP 2 LAST SIG_NAME M_D_CPU1_SA_DQ<31:0>
J 0
(-1560 4160);
DISPLAY 0.680851 (-1560 4160);
PAINT WHITE (-1560 4160);
WIRE 17 -1 (-3375 2700)(-3375 2750);
WIRE 17 -1 (-3375 2650)(-3375 2700);
WIRE 17 -1 (-4200 2750)(-3375 2750);
FORCEPROP 2 LAST SIG_NAME M_D_CPU1_SA_CB<7:0>
J 0
(-4110 2760);
DISPLAY 0.680851 (-4110 2760);
PAINT WHITE (-4110 2760);
WIRE 17 -1 (-3375 2600)(-3375 2650);
WIRE 17 -1 (-3375 2550)(-3375 2600);
WIRE 17 -1 (-3375 2500)(-3375 2550);
WIRE 17 -1 (-3375 2450)(-3375 2500);
WIRE 17 -1 (-3375 2400)(-3375 2450);
WIRE 17 -1 (-3375 2250)(-3375 2300);
WIRE 17 -1 (-3375 2200)(-3375 2250);
WIRE 17 -1 (-4200 2300)(-3375 2300);
FORCEPROP 2 LAST SIG_NAME M_D_CPU1_SB_CB<7:0>
J 0
(-4110 2310);
DISPLAY 0.680851 (-4110 2310);
PAINT WHITE (-4110 2310);
WIRE 17 -1 (-3375 3850)(-3375 3900);
WIRE 17 -1 (-3375 3900)(-3375 3950);
WIRE 17 -1 (-3375 3950)(-3375 4000);
WIRE 17 -1 (-3375 4000)(-3375 4050);
WIRE 17 -1 (-3375 4050)(-3375 4100);
WIRE 17 -1 (-3375 4100)(-3375 4150);
WIRE 17 -1 (-4200 4150)(-3375 4150);
FORCEPROP 2 LAST SIG_NAME M_D_CPU1_SA_CA<6:0>
J 0
(-4110 4160);
DISPLAY 0.680851 (-4110 4160);
PAINT WHITE (-4110 4160);
WIRE 17 -1 (-3375 3450)(-3375 3500);
WIRE 17 -1 (-3375 3500)(-3375 3550);
WIRE 17 -1 (-3375 3550)(-3375 3600);
WIRE 17 -1 (-3375 3600)(-3375 3650);
WIRE 17 -1 (-3375 3650)(-3375 3700);
WIRE 17 -1 (-3375 3700)(-3375 3750);
WIRE 17 -1 (-4200 3750)(-3375 3750);
FORCEPROP 2 LAST SIG_NAME M_D_CPU1_SB_CA<6:0>
J 0
(-4110 3760);
DISPLAY 0.680851 (-4110 3760);
PAINT WHITE (-4110 3760);
WIRE 17 -1 (-3375 2150)(-3375 2200);
WIRE 17 -1 (-3375 2100)(-3375 2150);
WIRE 17 -1 (-3375 2050)(-3375 2100);
WIRE 17 -1 (-3375 2000)(-3375 2050);
WIRE 17 -1 (-3375 1950)(-3375 2000);
WIRE 17 -1 (-1625 4000)(-1625 4050);
WIRE 17 -1 (-1625 3950)(-1625 4000);
WIRE 17 -1 (-1625 3900)(-1625 3950);
WIRE 17 -1 (-1625 3850)(-1625 3900);
WIRE 17 -1 (-1625 3800)(-1625 3850);
WIRE 17 -1 (-1625 3750)(-1625 3800);
WIRE 17 -1 (-1625 3700)(-1625 3750);
WIRE 17 -1 (-1625 3650)(-1625 3700);
WIRE 17 -1 (-1625 3600)(-1625 3650);
WIRE 17 -1 (-1625 3550)(-1625 3600);
WIRE 17 -1 (-1625 3500)(-1625 3550);
WIRE 17 -1 (-1625 3450)(-1625 3500);
WIRE 17 -1 (-1625 3400)(-1625 3450);
WIRE 17 -1 (-1625 3350)(-1625 3400);
WIRE 17 -1 (-1625 3300)(-1625 3350);
WIRE 17 -1 (-1625 3250)(-1625 3300);
WIRE 17 -1 (-1625 3200)(-1625 3250);
WIRE 17 -1 (-1625 3150)(-1625 3200);
WIRE 17 -1 (-1625 3100)(-1625 3150);
WIRE 17 -1 (-1625 3050)(-1625 3100);
WIRE 17 -1 (-1625 3000)(-1625 3050);
WIRE 17 -1 (-1625 2950)(-1625 3000);
WIRE 17 -1 (-1625 2900)(-1625 2950);
WIRE 17 -1 (-1625 2850)(-1625 2900);
WIRE 17 -1 (-1625 2800)(-1625 2850);
WIRE 17 -1 (-1625 2750)(-1625 2800);
WIRE 17 -1 (-1625 2700)(-1625 2750);
WIRE 17 -1 (-1625 2650)(-1625 2700);
WIRE 17 -1 (-1625 2600)(-1625 2650);
WIRE 17 -1 (-1625 2450)(-1625 2500);
WIRE 17 -1 (-1625 2400)(-1625 2450);
WIRE 17 -1 (-1625 2500)(-900 2500);
FORCEPROP 2 LAST SIG_NAME M_D_CPU1_SB_DQ<31:0>
J 0
(-1560 2510);
DISPLAY 0.680851 (-1560 2510);
PAINT WHITE (-1560 2510);
WIRE 17 -1 (-1625 2350)(-1625 2400);
WIRE 17 -1 (-1625 2300)(-1625 2350);
WIRE 17 -1 (-1625 2250)(-1625 2300);
WIRE 17 -1 (-1625 2200)(-1625 2250);
WIRE 17 -1 (-1625 2150)(-1625 2200);
WIRE 17 -1 (-1625 2100)(-1625 2150);
WIRE 17 -1 (-1625 2050)(-1625 2100);
WIRE 17 -1 (-1625 2000)(-1625 2050);
WIRE 17 -1 (-1625 1950)(-1625 2000);
WIRE 17 -1 (-1625 1900)(-1625 1950);
WIRE 17 -1 (-1625 1850)(-1625 1900);
WIRE 17 -1 (-1625 1800)(-1625 1850);
WIRE 17 -1 (-1625 1750)(-1625 1800);
WIRE 17 -1 (-1625 1700)(-1625 1750);
WIRE 17 -1 (-1625 1650)(-1625 1700);
WIRE 17 -1 (-1625 1600)(-1625 1650);
WIRE 17 -1 (-1625 1550)(-1625 1600);
WIRE 17 -1 (-1625 1500)(-1625 1550);
WIRE 17 -1 (-1625 1450)(-1625 1500);
WIRE 17 -1 (-1625 1400)(-1625 1450);
WIRE 17 -1 (-1625 1350)(-1625 1400);
WIRE 17 -1 (-1625 1300)(-1625 1350);
WIRE 17 -1 (-1625 1250)(-1625 1300);
WIRE 17 -1 (-1625 1200)(-1625 1250);
WIRE 17 -1 (-1625 1150)(-1625 1200);
WIRE 17 -1 (-1625 1100)(-1625 1150);
WIRE 17 -1 (-1625 1050)(-1625 1100);
WIRE 17 -1 (-1625 1000)(-1625 1050);
WIRE 17 -1 (-1625 950)(-1625 1000);
WIRE 17 -1 (1125 2300)(1125 2400);
WIRE 17 -1 (1125 2200)(1125 2300);
WIRE 17 -1 (1125 2400)(1125 2500);
WIRE 17 -1 (1125 2600)(1125 2500);
WIRE 17 -1 (1125 2600)(1125 2700);
WIRE 17 -1 (1125 2700)(1125 2800);
WIRE 17 -1 (1125 2800)(1125 2900);
WIRE 17 -1 (1125 2900)(1125 3000);
WIRE 17 -1 (1125 3000)(1125 3100);
WIRE 17 -1 (1125 3100)(2150 3100);
FORCEPROP 2 LAST SIG_NAME M_D_CPU1_SB_DQS_DP<9:0>
J 0
(1365 3110);
DISPLAY 0.680851 (1365 3110);
PAINT WHITE (1365 3110);
WIRE 17 -1 (1125 3250)(1125 3350);
WIRE 17 -1 (1125 3350)(1125 3450);
WIRE 17 -1 (1125 3450)(1125 3550);
WIRE 17 -1 (1125 3650)(1125 3550);
WIRE 17 -1 (1125 3650)(1125 3750);
WIRE 17 -1 (1125 3750)(1125 3850);
WIRE 17 -1 (1125 3850)(1125 3950);
WIRE 17 -1 (1125 3950)(1125 4050);
WIRE 17 -1 (1125 4050)(1125 4150);
WIRE 17 -1 (1125 4150)(2150 4150);
FORCEPROP 2 LAST SIG_NAME M_D_CPU1_SA_DQS_DP<9:0>
J 0
(1365 4160);
DISPLAY 0.680851 (1365 4160);
PAINT WHITE (1365 4160);
WIRE 17 -1 (1300 2150)(1300 2250);
WIRE 17 -1 (1300 2250)(1300 2350);
WIRE 17 -1 (1300 2350)(1300 2450);
WIRE 17 -1 (1300 2550)(1300 2450);
WIRE 17 -1 (1300 2550)(1300 2650);
WIRE 17 -1 (1300 2650)(1300 2750);
WIRE 17 -1 (1300 2750)(1300 2850);
WIRE 17 -1 (1300 2850)(1300 2950);
WIRE 17 -1 (1300 2950)(1300 3050);
WIRE 17 -1 (1300 3050)(2150 3050);
FORCEPROP 2 LAST SIG_NAME M_D_CPU1_SB_DQS_DN<9:0>
J 0
(1365 3060);
DISPLAY 0.680851 (1365 3060);
PAINT WHITE (1365 3060);
WIRE 17 -1 (1300 3200)(1300 3300);
WIRE 17 -1 (1300 3300)(1300 3400);
WIRE 17 -1 (1300 3400)(1300 3500);
WIRE 17 -1 (1300 3600)(1300 3500);
WIRE 17 -1 (1300 3600)(1300 3700);
WIRE 17 -1 (1300 3700)(1300 3800);
WIRE 17 -1 (1300 3800)(1300 3900);
WIRE 17 -1 (1300 3900)(1300 4000);
WIRE 17 -1 (1300 4000)(1300 4100);
WIRE 17 -1 (1300 4100)(2150 4100);
FORCEPROP 2 LAST SIG_NAME M_D_CPU1_SA_DQS_DN<9:0>
J 0
(1365 4110);
DISPLAY 0.680851 (1365 4110);
PAINT WHITE (1365 4110);
WIRE 16 -1 (50 350)(50 525);
WIRE 16 -1 (1050 525)(1050 475);
WIRE 16 -1 (2750 4625)(2750 4125);
WIRE 16 -1 (-4150 1950)(-4150 1675);
WIRE 16 -1 (-3100 -200)(-3100 -125);
WIRE 16 -1 (50 150)(50 -75);
WIRE 16 -1 (1675 -75)(1675 0);
WIRE 16 -1 (2750 475)(2750 875);
WIRE 16 -1 (4450 775)(4450 475);
WIRE 16 -1 (4450 825)(4450 775);
WIRE 16 -1 (4200 775)(4450 775);
WIRE 16 -1 (-3100 175)(-4200 175);
FORCEPROP 2 LAST SIG_NAME PD_CHD_CPU1_DIMM1_SAA
J 0
(-4112 184);
DISPLAY 0.680851 (-4112 184);
PAINT WHITE (-4112 184);
WIRE 16 -1 (-3100 75)(-3100 175);
WIRE 16 -1 (-3100 875)(-4200 875);
FORCEPROP 2 LAST SIG_NAME TP_CHD_CPU1_DIMM1_FRU_0
J 0
(-4112 884);
DISPLAY 0.680851 (-4112 884);
PAINT WHITE (-4112 884);
WIRE 16 -1 (-1900 1925)(-1725 1925);
WIRE 16 -1 (-4150 1675)(-3100 1675);
WIRE 16 -1 (-3100 1775)(-4200 1775);
FORCEPROP 2 LAST SIG_NAME M_D_CPU1_ALERT_N
J 0
(-4112 1784);
DISPLAY 0.680851 (-4112 1784);
PAINT WHITE (-4112 1784);
WIRE 16 -1 (-3100 1575)(-4125 1575);
FORCEPROP 2 LAST SIG_NAME I3C_SPD_DDRABCD_CPU1_LVC1_SDA
J 0
(-4135 1585);
DISPLAY 0.680851 (-4135 1585);
PAINT WHITE (-4135 1585);
WIRE 16 -1 (-3100 1625)(-4125 1625);
FORCEPROP 2 LAST SIG_NAME PD_CHD_CPU1_DIMM1_SAA
J 0
(-4135 1635);
DISPLAY 0.680851 (-4135 1635);
PAINT WHITE (-4135 1635);
WIRE 16 -1 (-4600 1425)(-4400 1425);
WIRE 16 -1 (-4600 1425)(-4600 1525);
WIRE 16 -1 (-3100 1525)(-4600 1525);
FORCEPROP 2 LAST SIG_NAME I3C_SPD_DDRABCD_CPU1_LVC1_SCL_R7
J 0
(-4160 1535);
DISPLAY 0.680851 (-4160 1535);
PAINT WHITE (-4160 1535);
WIRE 16 -1 (-3450 1825)(-3100 1825);
WIRE 16 -1 (-3450 1875)(-4200 1875);
FORCEPROP 2 LAST SIG_NAME RST_M_CD_CPU1_FPGA_N
J 0
(-4112 1884);
DISPLAY 0.680851 (-4112 1884);
PAINT WHITE (-4112 1884);
WIRE 16 -1 (-3450 1875)(-3450 1825);
WIRE 16 -1 (-3000 1350)(-3050 1350);
WIRE 16 -1 (-3000 1425)(-3000 1350);
WIRE 16 -1 (-4200 1425)(-3000 1425);
FORCEPROP 2 LAST SIG_NAME I3C_SPD_DDRABCD_CPU1_LVC1_SCL
J 0
(-3960 1435);
DISPLAY 0.680851 (-3960 1435);
PAINT WHITE (-3960 1435);
WIRE 16 -1 (-3100 1275)(-4200 1275);
FORCEPROP 2 LAST SIG_NAME PWRGD_CHD_CPU1_DIMM1
J 0
(-4112 1284);
DISPLAY 0.680851 (-4112 1284);
PAINT WHITE (-4112 1284);
WIRE 16 -1 (-3100 1175)(-4200 1175);
FORCEPROP 2 LAST SIG_NAME TP_CHD_CPU1_DIMM1_FRU_6
J 0
(-4112 1184);
DISPLAY 0.680851 (-4112 1184);
PAINT WHITE (-4112 1184);
WIRE 16 -1 (925 2525)(1200 2525);
WIRE 16 -1 (925 3975)(1200 3975);
WIRE 16 -1 (925 4075)(1200 4075);
WIRE 16 -1 (925 3875)(1200 3875);
WIRE 16 -1 (925 3775)(1200 3775);
WIRE 16 -1 (925 3675)(1200 3675);
WIRE 16 -1 (925 3475)(1200 3475);
WIRE 16 -1 (925 3575)(1200 3575);
WIRE 16 -1 (925 3375)(1200 3375);
WIRE 16 -1 (925 3275)(1200 3275);
WIRE 16 -1 (925 3175)(1200 3175);
WIRE 16 -1 (925 3025)(1200 3025);
WIRE 16 -1 (925 2925)(1200 2925);
WIRE 16 -1 (925 2825)(1200 2825);
WIRE 16 -1 (925 2725)(1200 2725);
WIRE 16 -1 (925 2625)(1200 2625);
WIRE 16 -1 (925 2425)(1200 2425);
WIRE 16 -1 (925 2325)(1200 2325);
WIRE 16 -1 (925 2225)(1200 2225);
WIRE 16 -1 (925 2125)(1200 2125);
WIRE 16 -1 (925 4125)(1025 4125);
WIRE 16 -1 (925 4025)(1025 4025);
WIRE 16 -1 (925 3925)(1025 3925);
WIRE 16 -1 (925 3825)(1025 3825);
WIRE 16 -1 (925 3725)(1025 3725);
WIRE 16 -1 (925 3625)(1025 3625);
WIRE 16 -1 (925 3525)(1025 3525);
WIRE 16 -1 (925 3425)(1025 3425);
WIRE 16 -1 (925 3325)(1025 3325);
WIRE 16 -1 (925 3225)(1025 3225);
WIRE 16 -1 (925 3075)(1025 3075);
WIRE 16 -1 (925 2975)(1025 2975);
WIRE 16 -1 (925 2875)(1025 2875);
WIRE 16 -1 (925 2775)(1025 2775);
WIRE 16 -1 (925 2675)(1025 2675);
WIRE 16 -1 (925 2575)(1025 2575);
WIRE 16 -1 (925 2475)(1025 2475);
WIRE 16 -1 (925 2375)(1025 2375);
WIRE 16 -1 (925 2175)(1025 2175);
WIRE 16 -1 (925 2275)(1025 2275);
WIRE 16 -1 (-1900 2625)(-1725 2625);
WIRE 16 -1 (-1900 1725)(-1725 1725);
WIRE 16 -1 (-3275 1975)(-3100 1975);
WIRE 16 -1 (3000 4125)(2750 4125);
WIRE 16 -1 (2750 4075)(3000 4075);
WIRE 16 -1 (2750 4125)(2750 4075);
WIRE 16 -1 (2750 4075)(2750 4025);
WIRE 16 -1 (3000 4025)(2750 4025);
WIRE 16 -1 (3000 3975)(2750 3975);
WIRE 16 -1 (2750 3925)(2750 3975);
WIRE 16 -1 (2750 3925)(3000 3925);
WIRE 16 -1 (2750 3875)(2750 3925);
WIRE 16 -1 (3000 3875)(2750 3875);
WIRE 16 -1 (2750 3825)(2750 3875);
WIRE 16 -1 (2750 3825)(3000 3825);
WIRE 16 -1 (2750 3775)(2750 3825);
WIRE 16 -1 (2750 3775)(3000 3775);
WIRE 16 -1 (2750 3725)(2750 3775);
WIRE 16 -1 (2750 3725)(3000 3725);
WIRE 16 -1 (2750 3675)(2750 3725);
WIRE 16 -1 (2750 3675)(3000 3675);
WIRE 16 -1 (2750 3625)(2750 3675);
WIRE 16 -1 (2750 3625)(3000 3625);
WIRE 16 -1 (2750 3575)(3000 3575);
WIRE 16 -1 (2750 3575)(2750 3625);
WIRE 16 -1 (2750 3525)(2750 3575);
WIRE 16 -1 (2750 3525)(3000 3525);
WIRE 16 -1 (2750 3475)(2750 3525);
WIRE 16 -1 (2750 3475)(3000 3475);
WIRE 16 -1 (2750 3425)(2750 3475);
WIRE 16 -1 (2750 3425)(3000 3425);
WIRE 16 -1 (2750 3375)(2750 3425);
WIRE 16 -1 (3000 3375)(2750 3375);
WIRE 16 -1 (2750 3325)(2750 3375);
WIRE 16 -1 (2750 3325)(3000 3325);
WIRE 16 -1 (2750 3275)(2750 3325);
WIRE 16 -1 (2750 3275)(3000 3275);
WIRE 16 -1 (2750 3225)(2750 3275);
WIRE 16 -1 (2750 3225)(3000 3225);
WIRE 16 -1 (2750 3175)(2750 3225);
WIRE 16 -1 (2750 3175)(3000 3175);
WIRE 16 -1 (2750 3125)(2750 3175);
WIRE 16 -1 (2750 3125)(3000 3125);
WIRE 16 -1 (2750 3075)(2750 3125);
WIRE 16 -1 (2750 3075)(3000 3075);
WIRE 16 -1 (2750 3025)(3000 3025);
WIRE 16 -1 (2750 3025)(2750 3075);
WIRE 16 -1 (2750 2975)(2750 3025);
WIRE 16 -1 (2750 2975)(3000 2975);
WIRE 16 -1 (2750 2925)(2750 2975);
WIRE 16 -1 (2750 2925)(3000 2925);
WIRE 16 -1 (2750 2875)(2750 2925);
WIRE 16 -1 (3000 2875)(2750 2875);
WIRE 16 -1 (2750 2825)(2750 2875);
WIRE 16 -1 (2750 2825)(3000 2825);
WIRE 16 -1 (2750 2775)(2750 2825);
WIRE 16 -1 (2750 2775)(3000 2775);
WIRE 16 -1 (2750 2725)(2750 2775);
WIRE 16 -1 (2750 2725)(3000 2725);
WIRE 16 -1 (2750 2675)(2750 2725);
WIRE 16 -1 (2750 2675)(3000 2675);
WIRE 16 -1 (2750 2625)(2750 2675);
WIRE 16 -1 (2750 2625)(3000 2625);
WIRE 16 -1 (2750 2575)(2750 2625);
WIRE 16 -1 (2750 2575)(3000 2575);
WIRE 16 -1 (2750 2525)(3000 2525);
WIRE 16 -1 (2750 2525)(2750 2575);
WIRE 16 -1 (2750 2475)(2750 2525);
WIRE 16 -1 (2750 2475)(3000 2475);
WIRE 16 -1 (2750 2425)(2750 2475);
WIRE 16 -1 (2750 2425)(3000 2425);
WIRE 16 -1 (2750 2375)(2750 2425);
WIRE 16 -1 (3000 2375)(2750 2375);
WIRE 16 -1 (2750 2325)(2750 2375);
WIRE 16 -1 (2750 2325)(3000 2325);
WIRE 16 -1 (2750 2275)(2750 2325);
WIRE 16 -1 (2750 2275)(3000 2275);
WIRE 16 -1 (2750 2225)(2750 2275);
WIRE 16 -1 (2750 2225)(3000 2225);
WIRE 16 -1 (2750 2175)(2750 2225);
WIRE 16 -1 (2750 2175)(3000 2175);
WIRE 16 -1 (2750 2125)(2750 2175);
WIRE 16 -1 (2750 2125)(3000 2125);
WIRE 16 -1 (2750 2075)(2750 2125);
WIRE 16 -1 (2750 2075)(3000 2075);
WIRE 16 -1 (2750 2025)(3000 2025);
WIRE 16 -1 (2750 2025)(2750 2075);
WIRE 16 -1 (2750 1975)(2750 2025);
WIRE 16 -1 (2750 1975)(3000 1975);
WIRE 16 -1 (2750 1925)(2750 1975);
WIRE 16 -1 (2750 1925)(3000 1925);
WIRE 16 -1 (2750 1875)(2750 1925);
WIRE 16 -1 (3000 1875)(2750 1875);
WIRE 16 -1 (2750 1825)(2750 1875);
WIRE 16 -1 (2750 1825)(3000 1825);
WIRE 16 -1 (2750 1775)(2750 1825);
WIRE 16 -1 (2750 1775)(3000 1775);
WIRE 16 -1 (2750 1725)(2750 1775);
WIRE 16 -1 (2750 1725)(3000 1725);
WIRE 16 -1 (2750 1675)(2750 1725);
WIRE 16 -1 (2750 1675)(3000 1675);
WIRE 16 -1 (2750 1625)(2750 1675);
WIRE 16 -1 (2750 1625)(3000 1625);
WIRE 16 -1 (2750 1575)(2750 1625);
WIRE 16 -1 (2750 1575)(3000 1575);
WIRE 16 -1 (2750 1525)(3000 1525);
WIRE 16 -1 (2750 1525)(2750 1575);
WIRE 16 -1 (2750 1475)(2750 1525);
WIRE 16 -1 (2750 1475)(3000 1475);
WIRE 16 -1 (2750 1425)(2750 1475);
WIRE 16 -1 (2750 1425)(3000 1425);
WIRE 16 -1 (2750 1375)(2750 1425);
WIRE 16 -1 (3000 1375)(2750 1375);
WIRE 16 -1 (2750 1325)(2750 1375);
WIRE 16 -1 (2750 1325)(3000 1325);
WIRE 16 -1 (2750 1275)(2750 1325);
WIRE 16 -1 (2750 1275)(3000 1275);
WIRE 16 -1 (2750 1225)(2750 1275);
WIRE 16 -1 (2750 1225)(3000 1225);
WIRE 16 -1 (2750 1175)(2750 1225);
WIRE 16 -1 (2750 1175)(3000 1175);
WIRE 16 -1 (2750 1125)(2750 1175);
WIRE 16 -1 (2750 1125)(3000 1125);
WIRE 16 -1 (2750 1075)(2750 1125);
WIRE 16 -1 (2750 1075)(3000 1075);
WIRE 16 -1 (2750 1025)(2750 1075);
WIRE 16 -1 (2750 1025)(3000 1025);
WIRE 16 -1 (2750 975)(3000 975);
WIRE 16 -1 (2750 975)(2750 1025);
WIRE 16 -1 (2750 925)(2750 975);
WIRE 16 -1 (2750 925)(3000 925);
WIRE 16 -1 (2750 875)(2750 925);
WIRE 16 -1 (2750 875)(3000 875);
WIRE 16 -1 (4200 4125)(4450 4125);
WIRE 16 -1 (4200 4075)(4450 4075);
WIRE 16 -1 (4450 4125)(4450 4075);
WIRE 16 -1 (4200 4025)(4450 4025);
WIRE 16 -1 (4450 4075)(4450 4025);
WIRE 16 -1 (4200 3975)(4450 3975);
WIRE 16 -1 (4450 4025)(4450 3975);
WIRE 16 -1 (4200 3925)(4450 3925);
WIRE 16 -1 (4450 3975)(4450 3925);
WIRE 16 -1 (4200 3875)(4450 3875);
WIRE 16 -1 (4450 3925)(4450 3875);
WIRE 16 -1 (4200 3825)(4450 3825);
WIRE 16 -1 (4450 3875)(4450 3825);
WIRE 16 -1 (4200 3775)(4450 3775);
WIRE 16 -1 (4450 3825)(4450 3775);
WIRE 16 -1 (4200 3725)(4450 3725);
WIRE 16 -1 (4450 3775)(4450 3725);
WIRE 16 -1 (4200 3675)(4450 3675);
WIRE 16 -1 (4450 3725)(4450 3675);
WIRE 16 -1 (4200 3625)(4450 3625);
WIRE 16 -1 (4450 3675)(4450 3625);
WIRE 16 -1 (4200 3575)(4450 3575);
WIRE 16 -1 (4450 3625)(4450 3575);
WIRE 16 -1 (4200 3525)(4450 3525);
WIRE 16 -1 (4450 3575)(4450 3525);
WIRE 16 -1 (4200 3475)(4450 3475);
WIRE 16 -1 (4450 3525)(4450 3475);
WIRE 16 -1 (4200 3425)(4450 3425);
WIRE 16 -1 (4450 3475)(4450 3425);
WIRE 16 -1 (4200 3375)(4450 3375);
WIRE 16 -1 (4450 3375)(4450 3425);
WIRE 16 -1 (4200 3325)(4450 3325);
WIRE 16 -1 (4450 3375)(4450 3325);
WIRE 16 -1 (4450 3275)(4200 3275);
WIRE 16 -1 (4450 3325)(4450 3275);
WIRE 16 -1 (4450 3225)(4200 3225);
WIRE 16 -1 (4450 3275)(4450 3225);
WIRE 16 -1 (4200 3175)(4450 3175);
WIRE 16 -1 (4450 3225)(4450 3175);
WIRE 16 -1 (4200 3125)(4450 3125);
WIRE 16 -1 (4450 3175)(4450 3125);
WIRE 16 -1 (4200 3075)(4450 3075);
WIRE 16 -1 (4450 3125)(4450 3075);
WIRE 16 -1 (4200 3025)(4450 3025);
WIRE 16 -1 (4450 3075)(4450 3025);
WIRE 16 -1 (4200 2975)(4450 2975);
WIRE 16 -1 (4450 3025)(4450 2975);
WIRE 16 -1 (4200 2925)(4450 2925);
WIRE 16 -1 (4450 2975)(4450 2925);
WIRE 16 -1 (4200 2875)(4450 2875);
WIRE 16 -1 (4450 2875)(4450 2925);
WIRE 16 -1 (4200 2825)(4450 2825);
WIRE 16 -1 (4450 2875)(4450 2825);
WIRE 16 -1 (4450 2775)(4200 2775);
WIRE 16 -1 (4450 2825)(4450 2775);
WIRE 16 -1 (4450 2725)(4200 2725);
WIRE 16 -1 (4450 2775)(4450 2725);
WIRE 16 -1 (4200 2675)(4450 2675);
WIRE 16 -1 (4450 2725)(4450 2675);
WIRE 16 -1 (4200 2625)(4450 2625);
WIRE 16 -1 (4450 2675)(4450 2625);
WIRE 16 -1 (4200 2575)(4450 2575);
WIRE 16 -1 (4450 2625)(4450 2575);
WIRE 16 -1 (4200 2525)(4450 2525);
WIRE 16 -1 (4450 2575)(4450 2525);
WIRE 16 -1 (4200 2475)(4450 2475);
WIRE 16 -1 (4450 2525)(4450 2475);
WIRE 16 -1 (4200 2425)(4450 2425);
WIRE 16 -1 (4450 2475)(4450 2425);
WIRE 16 -1 (4200 2375)(4450 2375);
WIRE 16 -1 (4450 2375)(4450 2425);
WIRE 16 -1 (4200 2325)(4450 2325);
WIRE 16 -1 (4450 2375)(4450 2325);
WIRE 16 -1 (4450 2275)(4200 2275);
WIRE 16 -1 (4450 2325)(4450 2275);
WIRE 16 -1 (4450 2225)(4200 2225);
WIRE 16 -1 (4450 2275)(4450 2225);
WIRE 16 -1 (4200 2175)(4450 2175);
WIRE 16 -1 (4450 2225)(4450 2175);
WIRE 16 -1 (4200 2125)(4450 2125);
WIRE 16 -1 (4450 2175)(4450 2125);
WIRE 16 -1 (4200 2075)(4450 2075);
WIRE 16 -1 (4450 2125)(4450 2075);
WIRE 16 -1 (4200 2025)(4450 2025);
WIRE 16 -1 (4450 2075)(4450 2025);
WIRE 16 -1 (4200 1975)(4450 1975);
WIRE 16 -1 (4450 2025)(4450 1975);
WIRE 16 -1 (4200 1925)(4450 1925);
WIRE 16 -1 (4450 1975)(4450 1925);
WIRE 16 -1 (4200 1875)(4450 1875);
WIRE 16 -1 (4450 1875)(4450 1925);
WIRE 16 -1 (4200 1825)(4450 1825);
WIRE 16 -1 (4450 1875)(4450 1825);
WIRE 16 -1 (4450 1775)(4200 1775);
WIRE 16 -1 (4450 1825)(4450 1775);
WIRE 16 -1 (4450 1725)(4200 1725);
WIRE 16 -1 (4450 1775)(4450 1725);
WIRE 16 -1 (4450 1675)(4200 1675);
WIRE 16 -1 (4450 1725)(4450 1675);
WIRE 16 -1 (4450 1625)(4200 1625);
WIRE 16 -1 (4450 1675)(4450 1625);
WIRE 16 -1 (4200 1575)(4450 1575);
WIRE 16 -1 (4450 1575)(4450 1625);
WIRE 16 -1 (4450 1525)(4200 1525);
WIRE 16 -1 (4450 1525)(4450 1575);
WIRE 16 -1 (4450 1475)(4200 1475);
WIRE 16 -1 (4450 1525)(4450 1475);
WIRE 16 -1 (4450 1425)(4200 1425);
WIRE 16 -1 (4450 1475)(4450 1425);
WIRE 16 -1 (4200 1375)(4450 1375);
WIRE 16 -1 (4450 1425)(4450 1375);
WIRE 16 -1 (4200 1325)(4450 1325);
WIRE 16 -1 (4450 1375)(4450 1325);
WIRE 16 -1 (4200 1275)(4450 1275);
WIRE 16 -1 (4450 1325)(4450 1275);
WIRE 16 -1 (4200 1225)(4450 1225);
WIRE 16 -1 (4450 1275)(4450 1225);
WIRE 16 -1 (4200 1175)(4450 1175);
WIRE 16 -1 (4450 1225)(4450 1175);
WIRE 16 -1 (4200 1125)(4450 1125);
WIRE 16 -1 (4450 1175)(4450 1125);
WIRE 16 -1 (4200 1075)(4450 1075);
WIRE 16 -1 (4450 1125)(4450 1075);
WIRE 16 -1 (4200 1025)(4450 1025);
WIRE 16 -1 (4450 1025)(4450 1075);
WIRE 16 -1 (4200 975)(4450 975);
WIRE 16 -1 (4450 1025)(4450 975);
WIRE 16 -1 (4200 875)(4450 875);
WIRE 16 -1 (4450 975)(4450 875);
WIRE 16 -1 (4450 875)(4450 825);
WIRE 16 -1 (4200 825)(4450 825);
WIRE 16 -1 (-3100 925)(-4200 925);
FORCEPROP 2 LAST SIG_NAME TP_CHD_CPU1_DIMM1_FRU_1
J 0
(-4112 934);
DISPLAY 0.680851 (-4112 934);
PAINT WHITE (-4112 934);
WIRE 16 -1 (-3100 975)(-4200 975);
FORCEPROP 2 LAST SIG_NAME TP_CHD_CPU1_DIMM1_FRU_2
J 0
(-4112 984);
DISPLAY 0.680851 (-4112 984);
PAINT WHITE (-4112 984);
WIRE 16 -1 (-3100 1025)(-4200 1025);
FORCEPROP 2 LAST SIG_NAME TP_CHD_CPU1_DIMM1_FRU_3
J 0
(-4112 1034);
DISPLAY 0.680851 (-4112 1034);
PAINT WHITE (-4112 1034);
WIRE 16 -1 (-3100 1075)(-4200 1075);
FORCEPROP 2 LAST SIG_NAME TP_CHD_CPU1_DIMM1_FRU_4
J 0
(-4112 1084);
DISPLAY 0.680851 (-4112 1084);
PAINT WHITE (-4112 1084);
WIRE 16 -1 (-3100 1125)(-4200 1125);
FORCEPROP 2 LAST SIG_NAME TP_CHD_CPU1_DIMM1_FRU_5
J 0
(-4112 1134);
DISPLAY 0.680851 (-4112 1134);
PAINT WHITE (-4112 1134);
WIRE 16 -1 (-3100 3275)(-4200 3275);
FORCEPROP 2 LAST SIG_NAME M_D_CPU1_SB_PAR
J 0
(-4112 3284);
DISPLAY 0.680851 (-4112 3284);
PAINT WHITE (-4112 3284);
WIRE 16 -1 (-3100 3325)(-4200 3325);
FORCEPROP 2 LAST SIG_NAME M_D_CPU1_SA_PAR
J 0
(-4112 3334);
DISPLAY 0.680851 (-4112 3334);
PAINT WHITE (-4112 3334);
WIRE 16 -1 (-3100 675)(-4200 675);
FORCEPROP 2 LAST SIG_NAME M_D_CPU1_SB_RSP<0>
J 0
(-4112 684);
DISPLAY 0.680851 (-4112 684);
PAINT WHITE (-4112 684);
WIRE 16 -1 (-3100 725)(-4200 725);
FORCEPROP 2 LAST SIG_NAME M_D_CPU1_SA_RSP<0>
J 0
(-4112 734);
DISPLAY 0.680851 (-4112 734);
PAINT WHITE (-4112 734);
WIRE 16 -1 (-1900 925)(-1725 925);
WIRE 16 -1 (-1900 975)(-1725 975);
WIRE 16 -1 (-1900 1025)(-1725 1025);
WIRE 16 -1 (-1900 1075)(-1725 1075);
WIRE 16 -1 (-1900 1125)(-1725 1125);
WIRE 16 -1 (-1900 1175)(-1725 1175);
WIRE 16 -1 (-1900 1225)(-1725 1225);
WIRE 16 -1 (-1900 1275)(-1725 1275);
WIRE 16 -1 (-1900 1325)(-1725 1325);
WIRE 16 -1 (-1900 1375)(-1725 1375);
WIRE 16 -1 (-1900 1425)(-1725 1425);
WIRE 16 -1 (-1900 1475)(-1725 1475);
WIRE 16 -1 (-1900 1525)(-1725 1525);
WIRE 16 -1 (-1900 1575)(-1725 1575);
WIRE 16 -1 (-1900 1625)(-1725 1625);
WIRE 16 -1 (-1900 1675)(-1725 1675);
WIRE 16 -1 (-1900 1775)(-1725 1775);
WIRE 16 -1 (-1900 1825)(-1725 1825);
WIRE 16 -1 (-1900 1875)(-1725 1875);
WIRE 16 -1 (-1900 1975)(-1725 1975);
WIRE 16 -1 (-1900 2025)(-1725 2025);
WIRE 16 -1 (-1900 2075)(-1725 2075);
WIRE 16 -1 (-1900 2125)(-1725 2125);
WIRE 16 -1 (-1900 2175)(-1725 2175);
WIRE 16 -1 (-1900 2225)(-1725 2225);
WIRE 16 -1 (-1900 2275)(-1725 2275);
WIRE 16 -1 (-1900 2325)(-1725 2325);
WIRE 16 -1 (-1900 2375)(-1725 2375);
WIRE 16 -1 (-1900 2425)(-1725 2425);
WIRE 16 -1 (-1900 2475)(-1725 2475);
WIRE 16 -1 (-1900 2575)(-1725 2575);
WIRE 16 -1 (-1900 2675)(-1725 2675);
WIRE 16 -1 (-1900 2725)(-1725 2725);
WIRE 16 -1 (-1900 2775)(-1725 2775);
WIRE 16 -1 (-1900 2825)(-1725 2825);
WIRE 16 -1 (-1900 2875)(-1725 2875);
WIRE 16 -1 (-1900 2925)(-1725 2925);
WIRE 16 -1 (-1900 2975)(-1725 2975);
WIRE 16 -1 (-1900 3025)(-1725 3025);
WIRE 16 -1 (-1900 3075)(-1725 3075);
WIRE 16 -1 (-1900 3125)(-1725 3125);
WIRE 16 -1 (-1900 3175)(-1725 3175);
WIRE 16 -1 (-1900 3225)(-1725 3225);
WIRE 16 -1 (-1900 3275)(-1725 3275);
WIRE 16 -1 (-1900 3325)(-1725 3325);
WIRE 16 -1 (-1900 3375)(-1725 3375);
WIRE 16 -1 (-1900 3425)(-1725 3425);
WIRE 16 -1 (-1900 3475)(-1725 3475);
WIRE 16 -1 (-1900 3525)(-1725 3525);
WIRE 16 -1 (-1900 3575)(-1725 3575);
WIRE 16 -1 (-1900 3625)(-1725 3625);
WIRE 16 -1 (-1900 3675)(-1725 3675);
WIRE 16 -1 (-1900 3725)(-1725 3725);
WIRE 16 -1 (-1900 3775)(-1725 3775);
WIRE 16 -1 (-1900 3825)(-1725 3825);
WIRE 16 -1 (-1900 3875)(-1725 3875);
WIRE 16 -1 (-1900 3925)(-1725 3925);
WIRE 16 -1 (-1900 3975)(-1725 3975);
WIRE 16 -1 (-1900 4025)(-1725 4025);
WIRE 16 -1 (-1900 4075)(-1725 4075);
WIRE 16 -1 (-3100 3025)(-4200 3025);
FORCEPROP 2 LAST SIG_NAME M_D_CPU1_SB_CS_N<1>
J 0
(-4112 3034);
DISPLAY 0.680851 (-4112 3034);
PAINT WHITE (-4112 3034);
WIRE 16 -1 (-3100 3175)(-4200 3175);
FORCEPROP 2 LAST SIG_NAME M_D_CPU1_SA_CS_N<1>
J 0
(-4112 3184);
DISPLAY 0.680851 (-4112 3184);
PAINT WHITE (-4112 3184);
WIRE 16 -1 (-3100 2975)(-4200 2975);
FORCEPROP 2 LAST SIG_NAME M_D_CPU1_SB_CS_N<0>
J 0
(-4112 2984);
DISPLAY 0.680851 (-4112 2984);
PAINT WHITE (-4112 2984);
WIRE 16 -1 (-3100 3125)(-4200 3125);
FORCEPROP 2 LAST SIG_NAME M_D_CPU1_SA_CS_N<0>
J 0
(-4112 3134);
DISPLAY 0.680851 (-4112 3134);
PAINT WHITE (-4112 3134);
WIRE 16 -1 (-3100 2875)(-4200 2875);
FORCEPROP 2 LAST SIG_NAME M_D_CPU1_CLK_DP<0>
J 0
(-4112 2884);
DISPLAY 0.680851 (-4112 2884);
PAINT WHITE (-4112 2884);
WIRE 16 -1 (-3100 2825)(-4200 2825);
FORCEPROP 2 LAST SIG_NAME M_D_CPU1_CLK_DN<0>
J 0
(-4112 2834);
DISPLAY 0.680851 (-4112 2834);
PAINT WHITE (-4112 2834);
WIRE 16 -1 (-3275 1925)(-3100 1925);
WIRE 16 -1 (-3275 2025)(-3100 2025);
WIRE 16 -1 (-3275 2075)(-3100 2075);
WIRE 16 -1 (-3275 2125)(-3100 2125);
WIRE 16 -1 (-3275 2175)(-3100 2175);
WIRE 16 -1 (-3275 2225)(-3100 2225);
WIRE 16 -1 (-3275 2375)(-3100 2375);
WIRE 16 -1 (-3275 2475)(-3100 2475);
WIRE 16 -1 (-3275 2525)(-3100 2525);
WIRE 16 -1 (-3275 2625)(-3100 2625);
WIRE 16 -1 (-3275 2675)(-3100 2675);
WIRE 16 -1 (-3275 3725)(-3100 3725);
WIRE 16 -1 (-3275 4125)(-3100 4125);
WIRE 16 -1 (-3275 3675)(-3100 3675);
WIRE 16 -1 (-3275 4075)(-3100 4075);
WIRE 16 -1 (-3275 3625)(-3100 3625);
WIRE 16 -1 (-3275 4025)(-3100 4025);
WIRE 16 -1 (-3275 3575)(-3100 3575);
WIRE 16 -1 (-3275 3975)(-3100 3975);
WIRE 16 -1 (-3275 3525)(-3100 3525);
WIRE 16 -1 (-3275 3925)(-3100 3925);
WIRE 16 -1 (-3275 3475)(-3100 3475);
WIRE 16 -1 (-3275 3875)(-3100 3875);
WIRE 16 -1 (-3275 3425)(-3100 3425);
WIRE 16 -1 (-3275 3825)(-3100 3825);
WIRE 16 -1 (-3275 2275)(-3100 2275);
WIRE 16 -1 (-3275 2425)(-3100 2425);
WIRE 16 -1 (-3275 2575)(-3100 2575);
WIRE 16 -1 (-3275 2725)(-3100 2725);
WIRE 16 -1 (-1900 4125)(-1725 4125);
WIRE 16 3135 (2300 750)(-300 750);
WIRE 16 3135 (2300 -550)(2300 750);
WIRE 16 3135 (-300 750)(-300 -550);
WIRE 16 3135 (-300 -550)(2300 -550);
WIRE 16 -1 (1675 0)(1675 150);
WIRE 16 -1 (1675 0)(1050 0);
WIRE 16 -1 (1050 0)(1050 150);
WIRE 16 -1 (1050 475)(1050 350);
WIRE 16 -1 (1675 475)(1050 475);
WIRE 16 -1 (1675 350)(1675 475);
DOT 1 (4450 775);
DOT 1 (4450 825);
DOT 1 (4450 875);
DOT 1 (4450 4075);
DOT 1 (4450 4025);
DOT 1 (4450 3975);
DOT 1 (4450 3925);
DOT 1 (4450 3875);
DOT 1 (4450 3825);
DOT 1 (4450 3775);
DOT 1 (4450 3725);
DOT 1 (4450 3625);
DOT 1 (4450 3675);
DOT 1 (4450 3575);
DOT 1 (4450 3525);
DOT 1 (4450 3475);
DOT 1 (4450 3425);
DOT 1 (4450 3375);
DOT 1 (4450 3325);
DOT 1 (4450 3275);
DOT 1 (4450 3225);
DOT 1 (4450 3175);
DOT 1 (4450 3125);
DOT 1 (4450 3075);
DOT 1 (4450 3025);
DOT 1 (4450 2975);
DOT 1 (4450 2925);
DOT 1 (4450 2875);
DOT 1 (4450 2825);
DOT 1 (4450 2775);
DOT 1 (4450 2725);
DOT 1 (4450 2675);
DOT 1 (4450 2625);
DOT 1 (4450 2575);
DOT 1 (4450 2525);
DOT 1 (4450 2475);
DOT 1 (4450 2425);
DOT 1 (4450 2375);
DOT 1 (4450 2325);
DOT 1 (4450 2275);
DOT 1 (4450 2225);
DOT 1 (4450 2175);
DOT 1 (4450 2125);
DOT 1 (4450 2075);
DOT 1 (4450 2025);
DOT 1 (4450 1975);
DOT 1 (4450 1925);
DOT 1 (4450 1875);
DOT 1 (4450 1825);
DOT 1 (4450 1775);
DOT 1 (4450 1725);
DOT 1 (4450 1675);
DOT 1 (4450 1575);
DOT 1 (4450 1625);
DOT 1 (4450 1525);
DOT 1 (4450 1475);
DOT 1 (4450 1425);
DOT 1 (4450 1375);
DOT 1 (4450 1325);
DOT 1 (4450 1275);
DOT 1 (4450 1225);
DOT 1 (4450 1175);
DOT 1 (4450 1125);
DOT 1 (4450 1075);
DOT 1 (4450 1025);
DOT 1 (4450 975);
DOT 1 (2750 4125);
DOT 1 (2750 4075);
DOT 1 (2750 3925);
DOT 1 (2750 3875);
DOT 1 (2750 3775);
DOT 1 (2750 3825);
DOT 1 (2750 3725);
DOT 1 (2750 3625);
DOT 1 (2750 3675);
DOT 1 (2750 3475);
DOT 1 (2750 3525);
DOT 1 (2750 3575);
DOT 1 (2750 3425);
DOT 1 (2750 3375);
DOT 1 (2750 3275);
DOT 1 (2750 3225);
DOT 1 (2750 3325);
DOT 1 (2750 3125);
DOT 1 (2750 3175);
DOT 1 (2750 3075);
DOT 1 (2750 3025);
DOT 1 (2750 2975);
DOT 1 (2750 2875);
DOT 1 (2750 2925);
DOT 1 (2750 2825);
DOT 1 (2750 2775);
DOT 1 (2750 2725);
DOT 1 (2750 2625);
DOT 1 (2750 2575);
DOT 1 (2750 2675);
DOT 1 (2750 2525);
DOT 1 (2750 2325);
DOT 1 (2750 2375);
DOT 1 (2750 2425);
DOT 1 (2750 2275);
DOT 1 (2750 2225);
DOT 1 (2750 2125);
DOT 1 (2750 2075);
DOT 1 (2750 2175);
DOT 1 (2750 1975);
DOT 1 (2750 2025);
DOT 1 (2750 1925);
DOT 1 (2750 1875);
DOT 1 (2750 1825);
DOT 1 (2750 1725);
DOT 1 (2750 1775);
DOT 1 (2750 1675);
DOT 1 (2750 1625);
DOT 1 (2750 1575);
DOT 1 (2750 1425);
DOT 1 (2750 1475);
DOT 1 (2750 1525);
DOT 1 (2750 1375);
DOT 1 (2750 1325);
DOT 1 (2750 1175);
DOT 1 (2750 1225);
DOT 1 (2750 1275);
DOT 1 (2750 1075);
DOT 1 (2750 1125);
DOT 1 (2750 1025);
DOT 1 (2750 925);
DOT 1 (2750 975);
DOT 1 (2750 875);
DOT 1 (1050 475);
DOT 1 (1675 0);
DOT 1 (2750 2475);
FORCENOTE
20210728 MODIFY FOR GT
(-4575 4800) 0;
DISPLAY LEFT (-4575 4800);
DISPLAY 2.510638 (-4575 4800);
PAINT PINK (-4575 4800);
QUIT
